FILE_TYPE = MACRO_DRAWING;
SET COLOR_WIRE YELLOW;
SET COLOR_PROP MONO;
SET COLOR_DOT WHITE;
SET COLOR_ARC YELLOW;
SET COLOR_BODY GREEN;
SET COLOR_NOTE MONO;
SET PROP_DISPLAY VALUE;
SET PAGE_NUMBER P170;
FORCEADD TTL08..1
(-1175 4375);
FORCEPROP 2 LASTPIN (-1025 4375) $PN 3
J 0
(-1015 4385);
DISPLAY 0.617021 (-1015 4385);
PAINT ORANGE (-1015 4385);
FORCEPROP 1 LAST PART_NUMBER D90404-001
J 0
(-1275 4225);
DISPLAY 0.617021 (-1275 4225);
PAINT BLUE (-1275 4225);
FORCEPROP 2 LASTPIN (-1325 4325) $PN 2
J 2
(-1335 4335);
DISPLAY 0.617021 (-1335 4335);
PAINT ORANGE (-1335 4335);
FORCEPROP 2 LASTPIN (-1325 4425) $PN 1
J 2
(-1335 4435);
DISPLAY 0.617021 (-1335 4435);
PAINT ORANGE (-1335 4435);
FORCEPROP 1 LAST LOCATION U8E1
J 0
(-1275 4600);
DISPLAY 0.617021 (-1275 4600);
PAINT AQUA (-1275 4600);
FORCEPROP 1 LAST MATERIAL IC
J 0
(-1275 4550);
DISPLAY 0.617021 (-1275 4550);
PAINT SKYBLUE (-1275 4550);
FORCEPROP 1 LAST VALUE 74LVC08A
J 0
(-1275 4500);
DISPLAY 0.617021 (-1275 4500);
PAINT SKYBLUE (-1275 4500);
FORCEPROP 1 LAST POWER_GROUP VCC=P3V3_STBY;GND=GND;TH=GND
J 0
(-1275 4175);
DISPLAY 0.617021 (-1275 4175);
PAINT ORANGE (-1275 4175);
FORCEPROP 2 LAST SEC_TYPE QFN15
J 0
(-1275 4650);
DISPLAY 1.021277 (-1275 4650);
PAINT ORANGE (-1275 4650);
DISPLAY INVISIBLE (-1275 4650);
FORCEPROP 2 LAST BOM_COST FAST_PROCHOT
J 0
(-1275 4700);
DISPLAY 1.021277 (-1275 4700);
PAINT ORANGE (-1275 4700);
DISPLAY INVISIBLE (-1275 4700);
FORCEPROP 2 LAST SEC 4
J 0
(-1275 4650);
DISPLAY 0.680851 (-1275 4650);
PAINT MONO (-1275 4650);
DISPLAY INVISIBLE (-1275 4650);
FORCEPROP 2 LAST ROOM FAST_PROCHOT
J 0
(-1275 4650);
DISPLAY 1.021277 (-1275 4650);
PAINT ORANGE (-1275 4650);
DISPLAY INVISIBLE (-1275 4650);
FORCEPROP 1 LAST PACK_TYPE QFN15
J 0
(-1275 4650);
DISPLAY 0.978723 (-1275 4650);
PAINT SKYBLUE (-1275 4650);
DISPLAY INVISIBLE (-1275 4650);
FORCEPROP 2 LAST CDS_LOCATION U8E1
J 0
(-1275 4600);
DISPLAY 0.617021 (-1275 4600);
PAINT AQUA (-1275 4600);
DISPLAY INVISIBLE (-1275 4600);
FORCEPROP 1 LAST PATH I10
J 0
(-800 4550);
DISPLAY 0.978723 (-800 4550);
PAINT BLUE (-800 4550);
DISPLAY INVISIBLE (-800 4550);
FORCEPROP 2 LAST CDS_LIB mstr_ttl
J 0
(-1175 4375);
PAINT MONO (-1175 4375);
DISPLAY INVISIBLE (-1175 4375);
FORCEADD TTL08..1
(-1175 3650);
FORCEPROP 1 LAST MATERIAL IC
J 0
(-1275 3825);
DISPLAY 0.617021 (-1275 3825);
PAINT SKYBLUE (-1275 3825);
FORCEPROP 1 LAST PART_NUMBER D90404-001
J 0
(-1275 3500);
DISPLAY 0.617021 (-1275 3500);
PAINT BLUE (-1275 3500);
FORCEPROP 2 LASTPIN (-1325 3600) $PN 5
J 2
(-1335 3610);
DISPLAY 0.617021 (-1335 3610);
PAINT ORANGE (-1335 3610);
FORCEPROP 2 LASTPIN (-1325 3700) $PN 4
J 2
(-1335 3710);
DISPLAY 0.617021 (-1335 3710);
PAINT ORANGE (-1335 3710);
FORCEPROP 1 LAST POWER_GROUP VCC=P3V3_STBY;GND=GND;TH=GND
J 0
(-1275 3450);
DISPLAY 0.617021 (-1275 3450);
PAINT ORANGE (-1275 3450);
FORCEPROP 2 LASTPIN (-1025 3650) $PN 6
J 0
(-1015 3660);
DISPLAY 0.617021 (-1015 3660);
PAINT ORANGE (-1015 3660);
FORCEPROP 1 LAST VALUE 74LVC08A
J 0
(-1275 3775);
DISPLAY 0.617021 (-1275 3775);
PAINT SKYBLUE (-1275 3775);
FORCEPROP 1 LAST LOCATION U8E1
J 0
(-1275 3875);
DISPLAY 0.617021 (-1275 3875);
PAINT AQUA (-1275 3875);
FORCEPROP 1 LAST PATH I11
J 0
(-800 3825);
DISPLAY 0.978723 (-800 3825);
PAINT BLUE (-800 3825);
DISPLAY INVISIBLE (-800 3825);
FORCEPROP 2 LAST SEC_TYPE QFN15
J 0
(-1275 3925);
DISPLAY 1.021277 (-1275 3925);
PAINT ORANGE (-1275 3925);
DISPLAY INVISIBLE (-1275 3925);
FORCEPROP 2 LAST BOM_COST FAST_PROCHOT
J 0
(-1275 3975);
DISPLAY 1.021277 (-1275 3975);
PAINT ORANGE (-1275 3975);
DISPLAY INVISIBLE (-1275 3975);
FORCEPROP 2 LAST SEC 3
J 0
(-1275 3925);
DISPLAY 0.680851 (-1275 3925);
PAINT MONO (-1275 3925);
DISPLAY INVISIBLE (-1275 3925);
FORCEPROP 2 LAST CDS_LOCATION U8E1
J 0
(-1275 3875);
DISPLAY 0.617021 (-1275 3875);
PAINT AQUA (-1275 3875);
DISPLAY INVISIBLE (-1275 3875);
FORCEPROP 2 LAST ROOM FAST_PROCHOT
J 0
(-1275 3925);
DISPLAY 1.021277 (-1275 3925);
PAINT ORANGE (-1275 3925);
DISPLAY INVISIBLE (-1275 3925);
FORCEPROP 1 LAST PACK_TYPE QFN15
J 0
(-1275 3925);
DISPLAY 0.978723 (-1275 3925);
PAINT SKYBLUE (-1275 3925);
DISPLAY INVISIBLE (-1275 3925);
FORCEPROP 2 LAST CDS_LIB mstr_ttl
J 0
(-1175 3650);
PAINT MONO (-1175 3650);
DISPLAY INVISIBLE (-1175 3650);
FORCEADD TTL08..1
(-25 4075);
FORCEPROP 1 LAST VALUE 74LVC08A
J 0
(-125 4200);
DISPLAY 0.617021 (-125 4200);
PAINT SKYBLUE (-125 4200);
FORCEPROP 1 LAST LOCATION U8E1
J 0
(-125 4300);
DISPLAY 0.617021 (-125 4300);
PAINT AQUA (-125 4300);
FORCEPROP 2 LASTPIN (-175 4125) $PN 12
J 2
(-185 4135);
DISPLAY 0.617021 (-185 4135);
PAINT ORANGE (-185 4135);
FORCEPROP 1 LAST MATERIAL IC
J 0
(-125 4250);
DISPLAY 0.617021 (-125 4250);
PAINT SKYBLUE (-125 4250);
FORCEPROP 2 LASTPIN (125 4075) $PN 11
J 0
(135 4085);
DISPLAY 0.617021 (135 4085);
PAINT ORANGE (135 4085);
FORCEPROP 1 LAST PART_NUMBER D90404-001
J 0
(-125 3925);
DISPLAY 0.617021 (-125 3925);
PAINT BLUE (-125 3925);
FORCEPROP 2 LASTPIN (-175 4025) $PN 13
J 2
(-185 4035);
DISPLAY 0.617021 (-185 4035);
PAINT ORANGE (-185 4035);
FORCEPROP 1 LAST POWER_GROUP VCC=P3V3_STBY;GND=GND;TH=GND
J 0
(-125 3875);
DISPLAY 0.617021 (-125 3875);
PAINT ORANGE (-125 3875);
FORCEPROP 1 LAST PATH I12
J 0
(350 4250);
DISPLAY 0.978723 (350 4250);
PAINT BLUE (350 4250);
DISPLAY INVISIBLE (350 4250);
FORCEPROP 2 LAST BOM_COST FAST_PROCHOT
J 0
(-125 4400);
DISPLAY 1.021277 (-125 4400);
PAINT ORANGE (-125 4400);
DISPLAY INVISIBLE (-125 4400);
FORCEPROP 2 LAST SEC 1
J 0
(-125 4350);
DISPLAY 0.680851 (-125 4350);
PAINT MONO (-125 4350);
DISPLAY INVISIBLE (-125 4350);
FORCEPROP 2 LAST SEC_TYPE QFN15
J 0
(-125 4350);
DISPLAY 1.021277 (-125 4350);
PAINT ORANGE (-125 4350);
DISPLAY INVISIBLE (-125 4350);
FORCEPROP 1 LAST PACK_TYPE QFN15
J 0
(-125 4350);
DISPLAY 0.978723 (-125 4350);
PAINT SKYBLUE (-125 4350);
DISPLAY INVISIBLE (-125 4350);
FORCEPROP 2 LAST ROOM FAST_PROCHOT
J 0
(-125 4350);
DISPLAY 1.021277 (-125 4350);
PAINT ORANGE (-125 4350);
DISPLAY INVISIBLE (-125 4350);
FORCEPROP 2 LAST CDS_LOCATION U8E1
J 0
(-125 4300);
DISPLAY 0.617021 (-125 4300);
PAINT AQUA (-125 4300);
DISPLAY INVISIBLE (-125 4300);
FORCEPROP 2 LAST CDS_LIB mstr_ttl
J 0
(-25 4075);
PAINT MONO (-25 4075);
DISPLAY INVISIBLE (-25 4075);
FORCEADD OFFPAGE..1
(-2300 4325);
FORCEPROP 2 LAST $XR0 200 
J 0
(-2552 4325);
DISPLAY 0.638298 (-2552 4325);
PAINT MONO (-2552 4325);
FORCEPROP 2 LAST PATH I15
J 0
(-2250 4400);
DISPLAY 1.021277 (-2250 4400);
PAINT ORANGE (-2250 4400);
DISPLAY INVISIBLE (-2250 4400);
FORCEPROP 2 LAST CDS_LIB mstr_standard
J 0
(-2300 4325);
PAINT MONO (-2300 4325);
DISPLAY INVISIBLE (-2300 4325);
FORCEPROP 1 LAST OFFPAGE TRUE
J 0
(-1975 4200);
DISPLAY 0.872340 (-1975 4200);
PAINT GREEN (-1975 4200);
DISPLAY INVISIBLE (-1975 4200);
FORCEPROP 1 LAST COMMENT_BODY TRUE
J 0
(-2175 4225);
DISPLAY 0.872340 (-2175 4225);
PAINT GREEN (-2175 4225);
DISPLAY INVISIBLE (-2175 4225);
FORCEADD OFFPAGE..1
(-2250 3700);
FORCEPROP 2 LAST $XR2 145 
J 0
(-2742 3700);
DISPLAY 0.638298 (-2742 3700);
PAINT MONO (-2742 3700);
FORCEPROP 2 LAST $XR1 120 
J 0
(-2622 3700);
DISPLAY 0.638298 (-2622 3700);
PAINT MONO (-2622 3700);
FORCEPROP 2 LAST $XR0 200 
J 0
(-2502 3700);
DISPLAY 0.638298 (-2502 3700);
PAINT MONO (-2502 3700);
FORCEPROP 2 LAST PATH I16
J 0
(-2200 3775);
DISPLAY 1.021277 (-2200 3775);
PAINT ORANGE (-2200 3775);
DISPLAY INVISIBLE (-2200 3775);
FORCEPROP 2 LAST CDS_LIB mstr_standard
J 0
(-2250 3700);
PAINT MONO (-2250 3700);
DISPLAY INVISIBLE (-2250 3700);
FORCEPROP 1 LAST OFFPAGE TRUE
J 0
(-1925 3575);
DISPLAY 0.872340 (-1925 3575);
PAINT GREEN (-1925 3575);
DISPLAY INVISIBLE (-1925 3575);
FORCEPROP 1 LAST COMMENT_BODY TRUE
J 0
(-2125 3600);
DISPLAY 0.872340 (-2125 3600);
PAINT GREEN (-2125 3600);
DISPLAY INVISIBLE (-2125 3600);
FORCEADD OFFPAGE..1
(-2250 3600);
FORCEPROP 2 LAST $XR2 145 
J 0
(-2742 3600);
DISPLAY 0.638298 (-2742 3600);
PAINT MONO (-2742 3600);
FORCEPROP 2 LAST $XR1 120 
J 0
(-2622 3600);
DISPLAY 0.638298 (-2622 3600);
PAINT MONO (-2622 3600);
FORCEPROP 2 LAST $XR0 200 
J 0
(-2502 3600);
DISPLAY 0.638298 (-2502 3600);
PAINT MONO (-2502 3600);
FORCEPROP 2 LAST PATH I17
J 0
(-2200 3675);
DISPLAY 1.021277 (-2200 3675);
PAINT ORANGE (-2200 3675);
DISPLAY INVISIBLE (-2200 3675);
FORCEPROP 2 LAST CDS_LIB mstr_standard
J 0
(-2250 3600);
PAINT MONO (-2250 3600);
DISPLAY INVISIBLE (-2250 3600);
FORCEPROP 1 LAST OFFPAGE TRUE
J 0
(-1925 3475);
DISPLAY 0.872340 (-1925 3475);
PAINT GREEN (-1925 3475);
DISPLAY INVISIBLE (-1925 3475);
FORCEPROP 1 LAST COMMENT_BODY TRUE
J 0
(-2125 3500);
DISPLAY 0.872340 (-2125 3500);
PAINT GREEN (-2125 3500);
DISPLAY INVISIBLE (-2125 3500);
FORCEADD OFFPAGE..2
(1025 4075);
FORCEPROP 2 LAST $XR0 191 
J 0
(1214 4075);
DISPLAY 0.638298 (1214 4075);
PAINT MONO (1214 4075);
FORCEPROP 2 LAST PATH I18
J 0
(1075 4150);
DISPLAY 1.021277 (1075 4150);
PAINT ORANGE (1075 4150);
DISPLAY INVISIBLE (1075 4150);
FORCEPROP 2 LAST CDS_LIB mstr_standard
J 0
(1025 4075);
PAINT MONO (1025 4075);
DISPLAY INVISIBLE (1025 4075);
FORCEPROP 1 LAST OFFPAGE TRUE
J 0
(1350 3950);
DISPLAY 0.872340 (1350 3950);
PAINT GREEN (1350 3950);
DISPLAY INVISIBLE (1350 3950);
FORCEPROP 1 LAST COMMENT_BODY TRUE
J 0
(980 3980);
DISPLAY 0.872340 (980 3980);
PAINT GREEN (980 3980);
DISPLAY INVISIBLE (980 3980);
FORCEADD OFFPAGE..1
(-3750 2525);
FORCEPROP 2 LAST $XR0 191 
J 0
(-4032 2525);
DISPLAY 0.638298 (-4032 2525);
PAINT MONO (-4032 2525);
FORCEPROP 2 LAST CDS_LIB mstr_standard
J 0
(-3750 2525);
PAINT MONO (-3750 2525);
DISPLAY INVISIBLE (-3750 2525);
FORCEPROP 2 LAST PATH I19
J 0
(-3700 2600);
DISPLAY 1.021277 (-3700 2600);
PAINT ORANGE (-3700 2600);
DISPLAY INVISIBLE (-3700 2600);
FORCEPROP 1 LAST OFFPAGE TRUE
J 0
(-3425 2400);
DISPLAY 0.872340 (-3425 2400);
PAINT GREEN (-3425 2400);
DISPLAY INVISIBLE (-3425 2400);
FORCEPROP 1 LAST COMMENT_BODY TRUE
J 0
(-3625 2425);
DISPLAY 0.872340 (-3625 2425);
PAINT GREEN (-3625 2425);
DISPLAY INVISIBLE (-3625 2425);
FORCEADD RES..2
(-2125 5250);
FORCEPROP 1 LAST PART_NUMBER G21796-072
J 0
(-2085 5125);
DISPLAY 0.617021 (-2085 5125);
PAINT BLUE (-2085 5125);
FORCEPROP 1 LAST WATTAGE 1/16W
J 0
(-2085 5225);
DISPLAY 0.617021 (-2085 5225);
PAINT SKYBLUE (-2085 5225);
FORCEPROP 1 LAST MATERIAL CHIP
J 0
(-2085 5175);
DISPLAY 0.617021 (-2085 5175);
PAINT SKYBLUE (-2085 5175);
FORCEPROP 1 LAST TOLERANCE 1%
J 0
(-2080 5275);
DISPLAY 0.617021 (-2080 5275);
PAINT SKYBLUE (-2080 5275);
FORCEPROP 1 LASTPIN (-2125 5350) $PN 1
J 0
(-2120 5312);
DISPLAY 0.617021 (-2120 5312);
PAINT ORANGE (-2120 5312);
FORCEPROP 1 LASTPIN (-2125 5150) $PN 2
J 0
(-2120 5160);
DISPLAY 0.617021 (-2120 5160);
PAINT ORANGE (-2120 5160);
FORCEPROP 1 LAST PACK_TYPE 0402
J 0
(-2085 5075);
DISPLAY 0.617021 (-2085 5075);
PAINT SKYBLUE (-2085 5075);
FORCEPROP 1 LAST LOCATION R2P3
J 0
(-2080 5375);
DISPLAY 0.617021 (-2080 5375);
PAINT AQUA (-2080 5375);
FORCEPROP 1 LAST VALUE 4.75K
J 0
(-2080 5325);
DISPLAY 0.617021 (-2080 5325);
PAINT SKYBLUE (-2080 5325);
FORCEPROP 2 LAST SEC_TYPE 0402
J 0
(-2075 5475);
DISPLAY 1.021277 (-2075 5475);
PAINT ORANGE (-2075 5475);
DISPLAY INVISIBLE (-2075 5475);
FORCEPROP 2 LAST BOM_COST FAST_PROCHOT
J 0
(-2075 5475);
DISPLAY 1.021277 (-2075 5475);
PAINT ORANGE (-2075 5475);
DISPLAY INVISIBLE (-2075 5475);
FORCEPROP 2 LAST SEC 1
J 0
(-2075 5475);
PAINT MONO (-2075 5475);
DISPLAY INVISIBLE (-2075 5475);
FORCEPROP 1 LAST PATH I2
J 0
(-2075 5425);
DISPLAY 0.978723 (-2075 5425);
PAINT WHITE (-2075 5425);
DISPLAY INVISIBLE (-2075 5425);
FORCEPROP 2 LAST ROOM FAST_PROCHOT
J 0
(-2075 5425);
DISPLAY 1.021277 (-2075 5425);
PAINT ORANGE (-2075 5425);
DISPLAY INVISIBLE (-2075 5425);
FORCEPROP 2 LAST CDS_LOCATION R2P3
J 0
(-2080 5375);
DISPLAY 0.617021 (-2080 5375);
PAINT AQUA (-2080 5375);
DISPLAY INVISIBLE (-2080 5375);
FORCEPROP 2 LAST CDS_LIB mstr_discrete
J 0
(-2125 5250);
PAINT MONO (-2125 5250);
DISPLAY INVISIBLE (-2125 5250);
FORCEADD TTL1G126_A..1
(-2525 2525);
FORCEPROP 1 LASTPIN (-2675 2525) $PN 2
J 2
(-2650 2535);
DISPLAY 0.617021 (-2650 2535);
PAINT WHITE (-2650 2535);
FORCEPROP 1 LAST LOCATION U1R2
J 0
(-2575 2725);
DISPLAY 0.617021 (-2575 2725);
PAINT AQUA (-2575 2725);
FORCEPROP 1 LAST VALUE 74HC1G126
J 0
(-2575 2625);
DISPLAY 0.617021 (-2575 2625);
PAINT SKYBLUE (-2575 2625);
FORCEPROP 1 LAST MATERIAL IC
J 0
(-2575 2675);
DISPLAY 0.617021 (-2575 2675);
PAINT SKYBLUE (-2575 2675);
FORCEPROP 1 LAST PART_NUMBER A79322-001
J 0
(-2425 2435);
DISPLAY 0.617021 (-2425 2435);
PAINT BLUE (-2425 2435);
FORCEPROP 1 LASTPIN (-2525 2425) $PN 1
J 0
(-2520 2375);
DISPLAY 0.617021 (-2520 2375);
PAINT WHITE (-2520 2375);
FORCEPROP 1 LASTPIN (-2375 2525) $PN 4
J 0
(-2410 2535);
DISPLAY 0.617021 (-2410 2535);
PAINT WHITE (-2410 2535);
FORCEPROP 1 LAST POWER_GROUP VCC=P3V3_STBY;GND=GND;
J 0
(-2425 2385);
DISPLAY 0.617021 (-2425 2385);
PAINT ORANGE (-2425 2385);
FORCEPROP 1 LAST PACK_TYPE SOT
J 0
(-2575 2775);
DISPLAY 0.978723 (-2575 2775);
PAINT SKYBLUE (-2575 2775);
DISPLAY INVISIBLE (-2575 2775);
FORCEPROP 2 LAST ROOM FAST_PROCHOT
J 0
(-2575 2775);
DISPLAY 1.021277 (-2575 2775);
PAINT ORANGE (-2575 2775);
DISPLAY INVISIBLE (-2575 2775);
FORCEPROP 1 LAST PATH I20
J 2
(-2630 2625);
DISPLAY 0.978723 (-2630 2625);
PAINT GREEN (-2630 2625);
DISPLAY INVISIBLE (-2630 2625);
FORCEPROP 2 LAST CDS_LOCATION U1R2
J 0
(-2575 2725);
DISPLAY 0.617021 (-2575 2725);
PAINT AQUA (-2575 2725);
DISPLAY INVISIBLE (-2575 2725);
FORCEPROP 2 LAST SEC 1
J 0
(-2575 2775);
DISPLAY 0.680851 (-2575 2775);
PAINT MONO (-2575 2775);
DISPLAY INVISIBLE (-2575 2775);
FORCEPROP 2 LAST BOM_COST FAST_PROCHOT
J 0
(-2575 2825);
DISPLAY 1.021277 (-2575 2825);
PAINT ORANGE (-2575 2825);
DISPLAY INVISIBLE (-2575 2825);
FORCEPROP 2 LAST SEC_TYPE SOT
J 0
(-2575 2775);
DISPLAY 1.021277 (-2575 2775);
PAINT ORANGE (-2575 2775);
DISPLAY INVISIBLE (-2575 2775);
FORCEPROP 2 LAST CDS_LIB mstr_ttl
J 0
(-2525 2525);
PAINT MONO (-2525 2525);
DISPLAY INVISIBLE (-2525 2525);
FORCEADD P3V3_STBY..1
(-2125 5475);
FORCEPROP 3 LASTPIN (-2125 5425) SIG_NAME P3V3_STBY\g
J 0
(-2115 5435);
DISPLAY 0.659574 (-2115 5435);
PAINT MONO (-2115 5435);
DISPLAY INVISIBLE (-2115 5435);
FORCEPROP 1 LAST VOLTAGE 3.3V
J 0
(-2170 5432);
DISPLAY 0.340426 (-2170 5432);
PAINT SKYBLUE (-2170 5432);
DISPLAY INVISIBLE (-2170 5432);
FORCEPROP 1 LAST SIZE 1B
J 0
(-2080 5497);
DISPLAY 0.340426 (-2080 5497);
PAINT GREEN (-2080 5497);
DISPLAY INVISIBLE (-2080 5497);
FORCEPROP 2 LAST CDS_LIB mstr_symbols
J 0
(-2125 5475);
PAINT ORANGE (-2125 5475);
DISPLAY INVISIBLE (-2125 5475);
FORCEPROP 1 LAST PATH I3
J 0
(-2080 5477);
DISPLAY 0.340426 (-2080 5477);
PAINT GREEN (-2080 5477);
DISPLAY INVISIBLE (-2080 5477);
FORCEPROP 1 LAST BODY_TYPE PLUMBING
J 0
(-2170 5432);
DISPLAY 0.340426 (-2170 5432);
PAINT GREEN (-2170 5432);
DISPLAY INVISIBLE (-2170 5432);
FORCEPROP 1 LAST HDL_POWER P3V3_STBY
J 0
(-2425 5350);
DISPLAY 0.872340 (-2425 5350);
PAINT ORANGE (-2425 5350);
DISPLAY INVISIBLE (-2425 5350);
FORCEADD CAP_A..1
(-5150 1325);
FORCEPROP 1 LASTPIN (-5150 1225) $PN 2
J 0
(-5140 1205);
DISPLAY 0.617021 (-5140 1205);
PAINT ORANGE (-5140 1205);
FORCEPROP 1 LASTPIN (-5150 1425) $PN 1
J 0
(-5140 1405);
DISPLAY 0.617021 (-5140 1405);
PAINT ORANGE (-5140 1405);
FORCEPROP 1 LAST LOCATION C1R27
J 0
(-5100 1425);
DISPLAY 0.617021 (-5100 1425);
PAINT AQUA (-5100 1425);
FORCEPROP 1 LAST PART_NUMBER A36096-030
J 0
(-5100 1175);
DISPLAY 0.617021 (-5100 1175);
PAINT BLUE (-5100 1175);
FORCEPROP 1 LAST VALUE 0.1UF
J 0
(-5100 1375);
DISPLAY 0.617021 (-5100 1375);
PAINT SKYBLUE (-5100 1375);
FORCEPROP 1 LAST TOLERANCE 10%
J 0
(-5100 1275);
DISPLAY 0.617021 (-5100 1275);
PAINT SKYBLUE (-5100 1275);
FORCEPROP 1 LAST PACK_TYPE 0402V
J 0
(-5100 1125);
DISPLAY 0.617021 (-5100 1125);
PAINT SKYBLUE (-5100 1125);
FORCEPROP 1 LAST VOLTAGE 16V
J 0
(-5100 1325);
DISPLAY 0.617021 (-5100 1325);
PAINT SKYBLUE (-5100 1325);
FORCEPROP 1 LAST MATERIAL X7R
J 0
(-5100 1225);
DISPLAY 0.617021 (-5100 1225);
PAINT SKYBLUE (-5100 1225);
FORCEPROP 2 LAST CDS_LIB dev_discrete
J 0
(-5150 1325);
PAINT ORANGE (-5150 1325);
DISPLAY INVISIBLE (-5150 1325);
FORCEPROP 1 LAST PATH I30
J 0
(-5100 1475);
DISPLAY 0.978723 (-5100 1475);
PAINT WHITE (-5100 1475);
DISPLAY INVISIBLE (-5100 1475);
FORCEPROP 2 LAST CDS_SEC 1
J 0
(-5100 1475);
PAINT ORANGE (-5100 1475);
DISPLAY INVISIBLE (-5100 1475);
FORCEPROP 2 LAST ROOM FAST_PROCHOT
J 0
(-5100 1475);
DISPLAY 1.021277 (-5100 1475);
PAINT ORANGE (-5100 1475);
DISPLAY INVISIBLE (-5100 1475);
FORCEPROP 2 LAST CDS_LOCATION C1R27
J 0
(-5100 1425);
DISPLAY 0.617021 (-5100 1425);
PAINT AQUA (-5100 1425);
DISPLAY INVISIBLE (-5100 1425);
FORCEPROP 2 LAST SEC_TYPE 0402V
J 0
(-5100 1525);
DISPLAY 1.021277 (-5100 1525);
PAINT ORANGE (-5100 1525);
DISPLAY INVISIBLE (-5100 1525);
FORCEPROP 2 LAST SEC 1
J 0
(-5100 1525);
DISPLAY 0.680851 (-5100 1525);
PAINT MONO (-5100 1525);
DISPLAY INVISIBLE (-5100 1525);
FORCEPROP 2 LAST BOM_COST FAST_PROCHOT
J 0
(-5100 1525);
DISPLAY 1.021277 (-5100 1525);
PAINT ORANGE (-5100 1525);
DISPLAY INVISIBLE (-5100 1525);
FORCEADD GND..1
(-5150 1050);
FORCEPROP 3 LASTPIN (-5150 1100) SIG_NAME GND\g
J 0
(-5140 1110);
DISPLAY 0.659574 (-5140 1110);
PAINT MONO (-5140 1110);
DISPLAY INVISIBLE (-5140 1110);
FORCEPROP 1 LAST VOLTAGE 0.0V
J 0
(-5195 1007);
DISPLAY 0.340426 (-5195 1007);
PAINT SKYBLUE (-5195 1007);
DISPLAY INVISIBLE (-5195 1007);
FORCEPROP 2 LAST CDS_LIB mstr_symbols
J 0
(-5150 1050);
PAINT ORANGE (-5150 1050);
DISPLAY INVISIBLE (-5150 1050);
FORCEPROP 1 LAST SIZE 1B
J 0
(-5075 1000);
DISPLAY 0.872340 (-5075 1000);
PAINT AQUA (-5075 1000);
DISPLAY INVISIBLE (-5075 1000);
FORCEPROP 1 LAST PATH I31
J 0
(-5075 1050);
DISPLAY 0.872340 (-5075 1050);
PAINT AQUA (-5075 1050);
DISPLAY INVISIBLE (-5075 1050);
FORCEPROP 1 LAST BODY_TYPE PLUMBING
J 0
(-5195 1007);
DISPLAY 0.340426 (-5195 1007);
PAINT GREEN (-5195 1007);
DISPLAY INVISIBLE (-5195 1007);
FORCEPROP 1 LAST HDL_POWER GND
J 0
(-5150 1200);
DISPLAY 0.872340 (-5150 1200);
PAINT GREEN (-5150 1200);
DISPLAY INVISIBLE (-5150 1200);
FORCEADD P3V3_STBY..1
(-5150 1575);
FORCEPROP 3 LASTPIN (-5150 1525) SIG_NAME P3V3_STBY\g
J 0
(-5140 1535);
DISPLAY 0.659574 (-5140 1535);
PAINT MONO (-5140 1535);
DISPLAY INVISIBLE (-5140 1535);
FORCEPROP 1 LAST VOLTAGE 3.3V
J 0
(-5195 1532);
DISPLAY 0.340426 (-5195 1532);
PAINT SKYBLUE (-5195 1532);
DISPLAY INVISIBLE (-5195 1532);
FORCEPROP 2 LAST CDS_LIB mstr_symbols
J 0
(-5150 1575);
PAINT ORANGE (-5150 1575);
DISPLAY INVISIBLE (-5150 1575);
FORCEPROP 1 LAST SIZE 1B
J 0
(-5105 1597);
DISPLAY 0.340426 (-5105 1597);
PAINT GREEN (-5105 1597);
DISPLAY INVISIBLE (-5105 1597);
FORCEPROP 1 LAST PATH I32
J 0
(-5105 1577);
DISPLAY 0.340426 (-5105 1577);
PAINT GREEN (-5105 1577);
DISPLAY INVISIBLE (-5105 1577);
FORCEPROP 1 LAST BODY_TYPE PLUMBING
J 0
(-5195 1532);
DISPLAY 0.340426 (-5195 1532);
PAINT GREEN (-5195 1532);
DISPLAY INVISIBLE (-5195 1532);
FORCEPROP 1 LAST HDL_POWER P3V3_STBY
J 0
(-5450 1450);
DISPLAY 0.872340 (-5450 1450);
PAINT ORANGE (-5450 1450);
DISPLAY INVISIBLE (-5450 1450);
FORCEADD CAP_A..1
(-200 4775);
FORCEPROP 1 LASTPIN (-200 4875) $PN 1
J 0
(-190 4855);
DISPLAY 0.617021 (-190 4855);
PAINT ORANGE (-190 4855);
FORCEPROP 1 LASTPIN (-200 4675) $PN 2
J 0
(-190 4655);
DISPLAY 0.617021 (-190 4655);
PAINT ORANGE (-190 4655);
FORCEPROP 1 LAST LOCATION C8D2
J 0
(-150 4875);
DISPLAY 0.617021 (-150 4875);
PAINT AQUA (-150 4875);
FORCEPROP 1 LAST VALUE 0.1UF
J 0
(-150 4825);
DISPLAY 0.617021 (-150 4825);
PAINT SKYBLUE (-150 4825);
FORCEPROP 1 LAST VOLTAGE 16V
J 0
(-150 4775);
DISPLAY 0.617021 (-150 4775);
PAINT SKYBLUE (-150 4775);
FORCEPROP 1 LAST TOLERANCE 10%
J 0
(-150 4725);
DISPLAY 0.617021 (-150 4725);
PAINT SKYBLUE (-150 4725);
FORCEPROP 1 LAST MATERIAL X7R
J 0
(-150 4675);
DISPLAY 0.617021 (-150 4675);
PAINT SKYBLUE (-150 4675);
FORCEPROP 1 LAST PART_NUMBER A36096-030
J 0
(-150 4625);
DISPLAY 0.617021 (-150 4625);
PAINT BLUE (-150 4625);
FORCEPROP 1 LAST PACK_TYPE 0402V
J 0
(-150 4575);
DISPLAY 0.617021 (-150 4575);
PAINT SKYBLUE (-150 4575);
FORCEPROP 2 LAST CDS_LOCATION C8D2
J 0
(-150 4875);
DISPLAY 0.617021 (-150 4875);
PAINT AQUA (-150 4875);
DISPLAY INVISIBLE (-150 4875);
FORCEPROP 1 LAST PATH I33
J 0
(-150 4925);
DISPLAY 0.978723 (-150 4925);
PAINT WHITE (-150 4925);
DISPLAY INVISIBLE (-150 4925);
FORCEPROP 2 LAST ROOM FAST_PROCHOT
J 0
(-150 4925);
DISPLAY 1.021277 (-150 4925);
PAINT ORANGE (-150 4925);
DISPLAY INVISIBLE (-150 4925);
FORCEPROP 2 LAST CDS_SEC 1
J 0
(-150 4925);
PAINT ORANGE (-150 4925);
DISPLAY INVISIBLE (-150 4925);
FORCEPROP 2 LAST SEC_TYPE 0402V
J 0
(-150 4975);
DISPLAY 1.021277 (-150 4975);
PAINT ORANGE (-150 4975);
DISPLAY INVISIBLE (-150 4975);
FORCEPROP 2 LAST BOM_COST FAST_PROCHOT
J 0
(-150 4975);
DISPLAY 1.021277 (-150 4975);
PAINT ORANGE (-150 4975);
DISPLAY INVISIBLE (-150 4975);
FORCEPROP 2 LAST SEC 1
J 0
(-150 4975);
DISPLAY 0.680851 (-150 4975);
PAINT MONO (-150 4975);
DISPLAY INVISIBLE (-150 4975);
FORCEPROP 2 LAST CDS_LIB dev_discrete
J 0
(-200 4775);
PAINT ORANGE (-200 4775);
DISPLAY INVISIBLE (-200 4775);
FORCEADD GND..1
(-200 4500);
FORCEPROP 3 LASTPIN (-200 4550) SIG_NAME GND\g
J 0
(-190 4560);
DISPLAY 0.659574 (-190 4560);
PAINT MONO (-190 4560);
DISPLAY INVISIBLE (-190 4560);
FORCEPROP 1 LAST PATH I34
J 0
(-125 4500);
DISPLAY 0.872340 (-125 4500);
PAINT AQUA (-125 4500);
DISPLAY INVISIBLE (-125 4500);
FORCEPROP 1 LAST SIZE 1B
J 0
(-125 4450);
DISPLAY 0.872340 (-125 4450);
PAINT AQUA (-125 4450);
DISPLAY INVISIBLE (-125 4450);
FORCEPROP 2 LAST CDS_LIB mstr_symbols
J 0
(-200 4500);
PAINT ORANGE (-200 4500);
DISPLAY INVISIBLE (-200 4500);
FORCEPROP 1 LAST VOLTAGE 0.0V
J 0
(-245 4457);
DISPLAY 0.340426 (-245 4457);
PAINT SKYBLUE (-245 4457);
DISPLAY INVISIBLE (-245 4457);
FORCEPROP 1 LAST BODY_TYPE PLUMBING
J 0
(-245 4457);
DISPLAY 0.340426 (-245 4457);
PAINT GREEN (-245 4457);
DISPLAY INVISIBLE (-245 4457);
FORCEPROP 1 LAST HDL_POWER GND
J 0
(-200 4650);
DISPLAY 0.872340 (-200 4650);
PAINT GREEN (-200 4650);
DISPLAY INVISIBLE (-200 4650);
FORCEADD P3V3_STBY..1
(-200 5025);
FORCEPROP 3 LASTPIN (-200 4975) SIG_NAME P3V3_STBY\g
J 0
(-190 4985);
DISPLAY 0.659574 (-190 4985);
PAINT MONO (-190 4985);
DISPLAY INVISIBLE (-190 4985);
FORCEPROP 1 LAST PATH I35
J 0
(-155 5027);
DISPLAY 0.340426 (-155 5027);
PAINT GREEN (-155 5027);
DISPLAY INVISIBLE (-155 5027);
FORCEPROP 1 LAST SIZE 1B
J 0
(-155 5047);
DISPLAY 0.340426 (-155 5047);
PAINT GREEN (-155 5047);
DISPLAY INVISIBLE (-155 5047);
FORCEPROP 1 LAST VOLTAGE 3.3V
J 0
(-245 4982);
DISPLAY 0.340426 (-245 4982);
PAINT SKYBLUE (-245 4982);
DISPLAY INVISIBLE (-245 4982);
FORCEPROP 2 LAST CDS_LIB mstr_symbols
J 0
(-200 5025);
PAINT ORANGE (-200 5025);
DISPLAY INVISIBLE (-200 5025);
FORCEPROP 1 LAST BODY_TYPE PLUMBING
J 0
(-245 4982);
DISPLAY 0.340426 (-245 4982);
PAINT GREEN (-245 4982);
DISPLAY INVISIBLE (-245 4982);
FORCEPROP 1 LAST HDL_POWER P3V3_STBY
J 0
(-500 4900);
DISPLAY 0.872340 (-500 4900);
PAINT ORANGE (-500 4900);
DISPLAY INVISIBLE (-500 4900);
FORCEADD TTL1G126_A..1
(-3500 4775);
FORCEPROP 1 LASTPIN (-3650 4775) $PN 2
J 2
(-3625 4785);
DISPLAY 0.617021 (-3625 4785);
PAINT WHITE (-3625 4785);
FORCEPROP 1 LASTPIN (-3350 4775) $PN 4
J 0
(-3385 4785);
DISPLAY 0.617021 (-3385 4785);
PAINT WHITE (-3385 4785);
FORCEPROP 1 LASTPIN (-3500 4675) $PN 1
J 0
(-3495 4625);
DISPLAY 0.617021 (-3495 4625);
PAINT WHITE (-3495 4625);
FORCEPROP 1 LAST PART_NUMBER A79322-001
J 0
(-3400 4685);
DISPLAY 0.617021 (-3400 4685);
PAINT BLUE (-3400 4685);
FORCEPROP 1 LAST VALUE 74HC1G126
J 0
(-3550 4875);
DISPLAY 0.617021 (-3550 4875);
PAINT SKYBLUE (-3550 4875);
FORCEPROP 1 LAST MATERIAL IC
J 0
(-3550 4925);
DISPLAY 0.617021 (-3550 4925);
PAINT SKYBLUE (-3550 4925);
FORCEPROP 1 LAST LOCATION U8D5
J 0
(-3550 4975);
DISPLAY 0.617021 (-3550 4975);
PAINT AQUA (-3550 4975);
FORCEPROP 1 LAST POWER_GROUP VCC=P3V3_STBY;GND=GND;
J 0
(-3400 4635);
DISPLAY 0.617021 (-3400 4635);
PAINT ORANGE (-3400 4635);
FORCEPROP 1 LAST PATH I38
J 2
(-3605 4875);
DISPLAY 0.978723 (-3605 4875);
PAINT GREEN (-3605 4875);
DISPLAY INVISIBLE (-3605 4875);
FORCEPROP 2 LAST CDS_LIB mstr_ttl
J 0
(-3500 4775);
PAINT ORANGE (-3500 4775);
DISPLAY INVISIBLE (-3500 4775);
FORCEPROP 1 LAST PACK_TYPE SOT
J 0
(-3550 5025);
DISPLAY 0.978723 (-3550 5025);
PAINT SKYBLUE (-3550 5025);
DISPLAY INVISIBLE (-3550 5025);
FORCEPROP 2 LAST ROOM PROC_SIDEBAND
J 0
(-3550 5025);
DISPLAY 1.021277 (-3550 5025);
PAINT ORANGE (-3550 5025);
DISPLAY INVISIBLE (-3550 5025);
FORCEPROP 2 LAST BOM_COST PROC_SIDEBAND
J 0
(-3550 5075);
DISPLAY 1.021277 (-3550 5075);
PAINT ORANGE (-3550 5075);
DISPLAY INVISIBLE (-3550 5075);
FORCEPROP 2 LAST SEC_TYPE SOT
J 0
(-3550 5025);
DISPLAY 1.021277 (-3550 5025);
PAINT ORANGE (-3550 5025);
DISPLAY INVISIBLE (-3550 5025);
FORCEPROP 2 LAST SEC 1
J 0
(-3550 5025);
DISPLAY 0.680851 (-3550 5025);
PAINT MONO (-3550 5025);
DISPLAY INVISIBLE (-3550 5025);
FORCEPROP 2 LAST CDS_LOCATION U8D5
J 0
(-3550 4975);
DISPLAY 0.617021 (-3550 4975);
PAINT AQUA (-3550 4975);
DISPLAY INVISIBLE (-3550 4975);
FORCEADD P3V3_STBY..1
(-1350 5350);
FORCEPROP 3 LASTPIN (-1350 5300) SIG_NAME P3V3_STBY\g
J 0
(-1340 5310);
DISPLAY 0.659574 (-1340 5310);
PAINT MONO (-1340 5310);
DISPLAY INVISIBLE (-1340 5310);
FORCEPROP 1 LAST SIZE 1B
J 0
(-1305 5372);
DISPLAY 0.340426 (-1305 5372);
PAINT GREEN (-1305 5372);
DISPLAY INVISIBLE (-1305 5372);
FORCEPROP 1 LAST PATH I39
J 0
(-1305 5352);
DISPLAY 0.340426 (-1305 5352);
PAINT GREEN (-1305 5352);
DISPLAY INVISIBLE (-1305 5352);
FORCEPROP 2 LAST CDS_LIB mstr_symbols
J 0
(-1350 5350);
PAINT ORANGE (-1350 5350);
DISPLAY INVISIBLE (-1350 5350);
FORCEPROP 1 LAST VOLTAGE 3.3V
J 0
(-1395 5307);
DISPLAY 0.340426 (-1395 5307);
PAINT SKYBLUE (-1395 5307);
DISPLAY INVISIBLE (-1395 5307);
FORCEPROP 1 LAST BODY_TYPE PLUMBING
J 0
(-1395 5307);
DISPLAY 0.340426 (-1395 5307);
PAINT GREEN (-1395 5307);
DISPLAY INVISIBLE (-1395 5307);
FORCEPROP 1 LAST HDL_POWER P3V3_STBY
J 0
(-1650 5225);
DISPLAY 0.872340 (-1650 5225);
PAINT ORANGE (-1650 5225);
DISPLAY INVISIBLE (-1650 5225);
FORCEADD TTL1G07_A..1
(-2400 4775);
FORCEPROP 2 LASTPIN (-2250 4775) $PN 4
J 0
(-2240 4785);
DISPLAY 0.617021 (-2240 4785);
PAINT MONO (-2240 4785);
FORCEPROP 1 LAST LOCATION U8D3
J 0
(-2450 4975);
DISPLAY 0.617021 (-2450 4975);
PAINT AQUA (-2450 4975);
FORCEPROP 2 LASTPIN (-2500 4775) $PN 2
J 2
(-2510 4785);
DISPLAY 0.617021 (-2510 4785);
PAINT MONO (-2510 4785);
FORCEPROP 1 LAST MATERIAL IC
J 0
(-2450 4925);
DISPLAY 0.617021 (-2450 4925);
PAINT SKYBLUE (-2450 4925);
FORCEPROP 1 LAST PART_NUMBER C88419-001
J 0
(-2450 4640);
DISPLAY 0.617021 (-2450 4640);
PAINT BLUE (-2450 4640);
FORCEPROP 1 LAST VALUE 74LVC1G07
J 1
(-2400 4875);
DISPLAY 0.617021 (-2400 4875);
PAINT SKYBLUE (-2400 4875);
FORCEPROP 1 LAST POWER_GROUP VCC=P3V3_STBY;GND=GND
J 1
(-2450 4585);
DISPLAY 0.617021 (-2450 4585);
PAINT ORANGE (-2450 4585);
FORCEPROP 2 LAST BOM_COST FAST_PROCHOT
J 0
(-2450 5075);
DISPLAY 1.021277 (-2450 5075);
PAINT ORANGE (-2450 5075);
DISPLAY INVISIBLE (-2450 5075);
FORCEPROP 2 LAST CDS_LIB mstr_ttl
J 0
(-2400 4775);
PAINT MONO (-2400 4775);
DISPLAY INVISIBLE (-2400 4775);
FORCEPROP 2 LAST CDS_SEC 1
J 0
(-2450 5025);
PAINT MONO (-2450 5025);
DISPLAY INVISIBLE (-2450 5025);
FORCEPROP 2 LAST $SEC 1
J 0
(-2450 5025);
PAINT MONO (-2450 5025);
DISPLAY INVISIBLE (-2450 5025);
FORCEPROP 2 LAST CDS_LOCATION U8D3
J 0
(-2450 4975);
DISPLAY 0.617021 (-2450 4975);
PAINT AQUA (-2450 4975);
DISPLAY INVISIBLE (-2450 4975);
FORCEPROP 1 LAST PATH I4
J 0
(-2350 4825);
DISPLAY 0.978723 (-2350 4825);
PAINT WHITE (-2350 4825);
DISPLAY INVISIBLE (-2350 4825);
FORCEPROP 2 LAST ROOM FAST_PROCHOT
J 0
(-2450 5025);
DISPLAY 1.021277 (-2450 5025);
PAINT ORANGE (-2450 5025);
DISPLAY INVISIBLE (-2450 5025);
FORCEPROP 1 LAST PACK_TYPE SOP
J 0
(-2450 5025);
DISPLAY 0.978723 (-2450 5025);
PAINT SKYBLUE (-2450 5025);
DISPLAY INVISIBLE (-2450 5025);
FORCEADD CAP_A..1
(-1350 5100);
FORCEPROP 1 LAST VALUE 0.1UF
J 0
(-1300 5150);
DISPLAY 0.617021 (-1300 5150);
PAINT SKYBLUE (-1300 5150);
FORCEPROP 1 LAST LOCATION C8E2
J 0
(-1300 5200);
DISPLAY 0.617021 (-1300 5200);
PAINT AQUA (-1300 5200);
FORCEPROP 1 LASTPIN (-1350 5200) $PN 1
J 0
(-1340 5180);
DISPLAY 0.617021 (-1340 5180);
PAINT ORANGE (-1340 5180);
FORCEPROP 1 LAST VOLTAGE 16V
J 0
(-1300 5100);
DISPLAY 0.617021 (-1300 5100);
PAINT SKYBLUE (-1300 5100);
FORCEPROP 1 LAST TOLERANCE 10%
J 0
(-1300 5050);
DISPLAY 0.617021 (-1300 5050);
PAINT SKYBLUE (-1300 5050);
FORCEPROP 1 LAST MATERIAL X7R
J 0
(-1300 5000);
DISPLAY 0.617021 (-1300 5000);
PAINT SKYBLUE (-1300 5000);
FORCEPROP 1 LASTPIN (-1350 5000) $PN 2
J 0
(-1340 4980);
DISPLAY 0.617021 (-1340 4980);
PAINT ORANGE (-1340 4980);
FORCEPROP 1 LAST PART_NUMBER A36096-030
J 0
(-1300 4950);
DISPLAY 0.617021 (-1300 4950);
PAINT BLUE (-1300 4950);
FORCEPROP 1 LAST PACK_TYPE 0402V
J 0
(-1300 4900);
DISPLAY 0.617021 (-1300 4900);
PAINT SKYBLUE (-1300 4900);
FORCEPROP 2 LAST CDS_SEC 1
J 0
(-1300 5250);
PAINT ORANGE (-1300 5250);
DISPLAY INVISIBLE (-1300 5250);
FORCEPROP 2 LAST SEC_TYPE 0402V
J 0
(-1300 5300);
DISPLAY 1.021277 (-1300 5300);
PAINT ORANGE (-1300 5300);
DISPLAY INVISIBLE (-1300 5300);
FORCEPROP 2 LAST ROOM PROC_SIDEBAND
J 0
(-1300 5250);
DISPLAY 1.021277 (-1300 5250);
PAINT ORANGE (-1300 5250);
DISPLAY INVISIBLE (-1300 5250);
FORCEPROP 2 LAST SEC 1
J 0
(-1300 5300);
DISPLAY 0.680851 (-1300 5300);
PAINT MONO (-1300 5300);
DISPLAY INVISIBLE (-1300 5300);
FORCEPROP 1 LAST PATH I40
J 0
(-1300 5250);
DISPLAY 0.978723 (-1300 5250);
PAINT WHITE (-1300 5250);
DISPLAY INVISIBLE (-1300 5250);
FORCEPROP 2 LAST BOM_COST PROC_SIDEBAND
J 0
(-1300 5300);
DISPLAY 1.021277 (-1300 5300);
PAINT ORANGE (-1300 5300);
DISPLAY INVISIBLE (-1300 5300);
FORCEPROP 2 LAST CDS_LOCATION C8E2
J 0
(-1300 5200);
DISPLAY 0.617021 (-1300 5200);
PAINT AQUA (-1300 5200);
DISPLAY INVISIBLE (-1300 5200);
FORCEPROP 2 LAST CDS_LIB dev_discrete
J 0
(-1350 5100);
PAINT ORANGE (-1350 5100);
DISPLAY INVISIBLE (-1350 5100);
FORCEADD GND..1
(-1350 4825);
FORCEPROP 3 LASTPIN (-1350 4875) SIG_NAME GND\g
J 0
(-1340 4885);
DISPLAY 0.659574 (-1340 4885);
PAINT MONO (-1340 4885);
DISPLAY INVISIBLE (-1340 4885);
FORCEPROP 1 LAST SIZE 1B
J 0
(-1275 4775);
DISPLAY 0.872340 (-1275 4775);
PAINT AQUA (-1275 4775);
DISPLAY INVISIBLE (-1275 4775);
FORCEPROP 1 LAST PATH I41
J 0
(-1275 4825);
DISPLAY 0.872340 (-1275 4825);
PAINT AQUA (-1275 4825);
DISPLAY INVISIBLE (-1275 4825);
FORCEPROP 2 LAST CDS_LIB mstr_symbols
J 0
(-1350 4825);
PAINT ORANGE (-1350 4825);
DISPLAY INVISIBLE (-1350 4825);
FORCEPROP 1 LAST VOLTAGE 0.0V
J 0
(-1395 4782);
DISPLAY 0.340426 (-1395 4782);
PAINT SKYBLUE (-1395 4782);
DISPLAY INVISIBLE (-1395 4782);
FORCEPROP 1 LAST BODY_TYPE PLUMBING
J 0
(-1395 4782);
DISPLAY 0.340426 (-1395 4782);
PAINT GREEN (-1395 4782);
DISPLAY INVISIBLE (-1395 4782);
FORCEPROP 1 LAST HDL_POWER GND
J 0
(-1350 4975);
DISPLAY 0.872340 (-1350 4975);
PAINT GREEN (-1350 4975);
DISPLAY INVISIBLE (-1350 4975);
FORCEADD CAP..1
(-3700 4250);
FORCEPROP 1 LASTPIN (-3700 4150) $PN 2
J 0
(-3690 4130);
DISPLAY 0.617021 (-3690 4130);
PAINT ORANGE (-3690 4130);
FORCEPROP 1 LASTPIN (-3700 4350) $PN 1
J 0
(-3690 4330);
DISPLAY 0.617021 (-3690 4330);
PAINT ORANGE (-3690 4330);
FORCEPROP 1 LAST PACK_TYPE 0402LF
J 0
(-3550 4050);
DISPLAY 0.617021 (-3550 4050);
PAINT SKYBLUE (-3550 4050);
FORCEPROP 1 LAST VOLTAGE 50V
J 0
(-3550 4250);
DISPLAY 0.617021 (-3550 4250);
PAINT SKYBLUE (-3550 4250);
FORCEPROP 1 LAST TOLERANCE 10%
J 0
(-3550 4200);
DISPLAY 0.617021 (-3550 4200);
PAINT SKYBLUE (-3550 4200);
FORCEPROP 1 LAST MATERIAL EMPTY
J 0
(-3550 4150);
DISPLAY 0.617021 (-3550 4150);
PAINT RED (-3550 4150);
FORCEPROP 1 LAST LOCATION C8D3
J 0
(-3550 4350);
DISPLAY 0.617021 (-3550 4350);
PAINT AQUA (-3550 4350);
FORCEPROP 1 LAST VALUE 470PF
J 0
(-3550 4300);
DISPLAY 0.617021 (-3550 4300);
PAINT SKYBLUE (-3550 4300);
FORCEPROP 1 LAST PART_NUMBER A36096-049
J 0
(-3550 4100);
DISPLAY 0.617021 (-3550 4100);
PAINT BLUE (-3550 4100);
FORCEPROP 2 LAST SEC_TYPE 0402LF
J 0
(-3650 4450);
DISPLAY 1.021277 (-3650 4450);
PAINT ORANGE (-3650 4450);
DISPLAY INVISIBLE (-3650 4450);
FORCEPROP 2 LAST SEC 1
J 0
(-3650 4450);
DISPLAY 0.680851 (-3650 4450);
PAINT MONO (-3650 4450);
DISPLAY INVISIBLE (-3650 4450);
FORCEPROP 2 LAST CDS_LIB mstr_discrete
J 0
(-3700 4250);
PAINT ORANGE (-3700 4250);
DISPLAY INVISIBLE (-3700 4250);
FORCEPROP 2 LAST ROOM PROC_SIDEBAND
J 0
(-3650 4400);
DISPLAY 1.021277 (-3650 4400);
PAINT ORANGE (-3650 4400);
DISPLAY INVISIBLE (-3650 4400);
FORCEPROP 1 LAST PATH I42
J 0
(-3650 4400);
DISPLAY 0.978723 (-3650 4400);
PAINT WHITE (-3650 4400);
DISPLAY INVISIBLE (-3650 4400);
FORCEPROP 2 LAST BOM_COST PROC_SIDEBAND
J 0
(-3650 4450);
DISPLAY 1.021277 (-3650 4450);
PAINT ORANGE (-3650 4450);
DISPLAY INVISIBLE (-3650 4450);
FORCEPROP 2 LAST CDS_LOCATION C8D3
J 0
(-3550 4350);
DISPLAY 0.617021 (-3550 4350);
PAINT AQUA (-3550 4350);
DISPLAY INVISIBLE (-3550 4350);
FORCEADD GND..1
(-3700 3950);
FORCEPROP 3 LASTPIN (-3700 4000) SIG_NAME GND\g
J 0
(-3690 4010);
DISPLAY 0.659574 (-3690 4010);
PAINT MONO (-3690 4010);
DISPLAY INVISIBLE (-3690 4010);
FORCEPROP 1 LAST VOLTAGE 0.0V
J 0
(-3745 3907);
DISPLAY 0.340426 (-3745 3907);
PAINT SKYBLUE (-3745 3907);
DISPLAY INVISIBLE (-3745 3907);
FORCEPROP 2 LAST CDS_LIB mstr_symbols
J 0
(-3700 3950);
PAINT ORANGE (-3700 3950);
DISPLAY INVISIBLE (-3700 3950);
FORCEPROP 1 LAST SIZE 1B
J 0
(-3625 3900);
DISPLAY 0.872340 (-3625 3900);
PAINT AQUA (-3625 3900);
DISPLAY INVISIBLE (-3625 3900);
FORCEPROP 1 LAST PATH I43
J 0
(-3625 3950);
DISPLAY 0.872340 (-3625 3950);
PAINT AQUA (-3625 3950);
DISPLAY INVISIBLE (-3625 3950);
FORCEPROP 1 LAST BODY_TYPE PLUMBING
J 0
(-3745 3907);
DISPLAY 0.340426 (-3745 3907);
PAINT GREEN (-3745 3907);
DISPLAY INVISIBLE (-3745 3907);
FORCEPROP 1 LAST HDL_POWER GND
J 0
(-3700 4100);
DISPLAY 0.872340 (-3700 4100);
PAINT GREEN (-3700 4100);
DISPLAY INVISIBLE (-3700 4100);
FORCEADD OFFPAGE..1
(-5000 4775);
FORCEPROP 2 LAST $XR2 146 
J 0
(-5492 4775);
DISPLAY 0.638298 (-5492 4775);
PAINT MONO (-5492 4775);
FORCEPROP 2 LAST $XR1 120 
J 0
(-5372 4775);
DISPLAY 0.638298 (-5372 4775);
PAINT MONO (-5372 4775);
FORCEPROP 2 LAST $XR0 199 
J 0
(-5252 4775);
DISPLAY 0.638298 (-5252 4775);
PAINT MONO (-5252 4775);
FORCEPROP 2 LAST PATH I44
J 0
(-5275 4825);
DISPLAY 1.021277 (-5275 4825);
PAINT ORANGE (-5275 4825);
DISPLAY INVISIBLE (-5275 4825);
FORCEPROP 2 LAST CDS_LIB mstr_standard
J 0
(-5000 4775);
PAINT ORANGE (-5000 4775);
DISPLAY INVISIBLE (-5000 4775);
FORCEPROP 1 LAST OFFPAGE TRUE
J 0
(-4675 4650);
DISPLAY 0.872340 (-4675 4650);
PAINT GREEN (-4675 4650);
DISPLAY INVISIBLE (-4675 4650);
FORCEPROP 1 LAST COMMENT_BODY TRUE
J 0
(-4875 4675);
DISPLAY 0.872340 (-4875 4675);
PAINT GREEN (-4875 4675);
DISPLAY INVISIBLE (-4875 4675);
FORCEADD TTL1G07_A..1
(-1225 2525);
FORCEPROP 1 LAST POWER_GROUP VCC=P3V3_STBY;GND=GND
J 1
(-1275 2335);
DISPLAY 0.617021 (-1275 2335);
PAINT ORANGE (-1275 2335);
FORCEPROP 1 LAST PART_NUMBER C88419-001
J 0
(-1275 2390);
DISPLAY 0.617021 (-1275 2390);
PAINT BLUE (-1275 2390);
FORCEPROP 1 LAST MATERIAL IC
J 0
(-1275 2675);
DISPLAY 0.617021 (-1275 2675);
PAINT SKYBLUE (-1275 2675);
FORCEPROP 1 LAST VALUE 74LVC1G07
J 1
(-1225 2625);
DISPLAY 0.617021 (-1225 2625);
PAINT SKYBLUE (-1225 2625);
FORCEPROP 1 LAST LOCATION U1R1
J 0
(-1275 2725);
DISPLAY 0.617021 (-1275 2725);
PAINT AQUA (-1275 2725);
FORCEPROP 2 LASTPIN (-1075 2525) $PN 4
J 0
(-1065 2535);
DISPLAY 0.617021 (-1065 2535);
PAINT ORANGE (-1065 2535);
FORCEPROP 2 LASTPIN (-1325 2525) $PN 2
J 2
(-1335 2535);
DISPLAY 0.617021 (-1335 2535);
PAINT ORANGE (-1335 2535);
FORCEPROP 0 LAST BOM_COST FAST_PROCHOT
J 0
(-1275 2925);
DISPLAY 1.021277 (-1275 2925);
PAINT ORANGE (-1275 2925);
DISPLAY INVISIBLE (-1275 2925);
FORCEPROP 2 LAST SEC_TYPE SOP
J 0
(-1275 2775);
DISPLAY 1.021277 (-1275 2775);
PAINT ORANGE (-1275 2775);
DISPLAY INVISIBLE (-1275 2775);
FORCEPROP 2 LAST SEC 1
J 0
(-1275 2775);
DISPLAY 0.680851 (-1275 2775);
PAINT MONO (-1275 2775);
DISPLAY INVISIBLE (-1275 2775);
FORCEPROP 2 LAST CDS_LOCATION U1R1
J 0
(-1275 2725);
DISPLAY 0.617021 (-1275 2725);
PAINT AQUA (-1275 2725);
DISPLAY INVISIBLE (-1275 2725);
FORCEPROP 1 LAST PACK_TYPE SOP
J 0
(-1275 2775);
DISPLAY 0.978723 (-1275 2775);
PAINT SKYBLUE (-1275 2775);
DISPLAY INVISIBLE (-1275 2775);
FORCEPROP 1 LAST PATH I46
J 0
(-1175 2575);
DISPLAY 0.978723 (-1175 2575);
PAINT WHITE (-1175 2575);
DISPLAY INVISIBLE (-1175 2575);
FORCEPROP 0 LAST ROOM FAST_PROCHOT
J 0
(-1275 2825);
DISPLAY 1.021277 (-1275 2825);
PAINT ORANGE (-1275 2825);
DISPLAY INVISIBLE (-1275 2825);
FORCEPROP 2 LAST CDS_LIB mstr_ttl
J 0
(-1225 2525);
PAINT MONO (-1225 2525);
DISPLAY INVISIBLE (-1225 2525);
FORCEADD OFFPAGE..2
(125 2525);
FORCEPROP 2 LAST $XR3 146 
J 0
(644 2525);
DISPLAY 0.638298 (644 2525);
PAINT MONO (644 2525);
FORCEPROP 2 LAST $XR2 95 
J 0
(554 2525);
DISPLAY 0.638298 (554 2525);
PAINT MONO (554 2525);
FORCEPROP 2 LAST $XR1 133 
J 0
(434 2525);
DISPLAY 0.638298 (434 2525);
PAINT MONO (434 2525);
FORCEPROP 2 LAST $XR0 119 
J 0
(314 2525);
DISPLAY 0.638298 (314 2525);
PAINT MONO (314 2525);
FORCEPROP 2 LAST PATH I47
J 0
(175 2600);
DISPLAY 1.021277 (175 2600);
PAINT ORANGE (175 2600);
DISPLAY INVISIBLE (175 2600);
FORCEPROP 2 LAST CDS_LIB mstr_standard
J 0
(125 2525);
PAINT MONO (125 2525);
DISPLAY INVISIBLE (125 2525);
FORCEPROP 1 LAST OFFPAGE TRUE
J 0
(450 2400);
DISPLAY 0.872340 (450 2400);
PAINT GREEN (450 2400);
DISPLAY INVISIBLE (450 2400);
FORCEPROP 1 LAST COMMENT_BODY TRUE
J 0
(80 2430);
DISPLAY 0.872340 (80 2430);
PAINT GREEN (80 2430);
DISPLAY INVISIBLE (80 2430);
FORCEADD P3V3_STBY..1
(-1600 1950);
FORCEPROP 3 LASTPIN (-1600 1900) SIG_NAME P3V3_STBY\g
J 0
(-1590 1910);
DISPLAY 0.659574 (-1590 1910);
PAINT MONO (-1590 1910);
DISPLAY INVISIBLE (-1590 1910);
FORCEPROP 1 LAST VOLTAGE 3.3V
J 0
(-1645 1907);
DISPLAY 0.340426 (-1645 1907);
PAINT SKYBLUE (-1645 1907);
DISPLAY INVISIBLE (-1645 1907);
FORCEPROP 1 LAST PATH I48
J 0
(-1555 1952);
DISPLAY 0.340426 (-1555 1952);
PAINT GREEN (-1555 1952);
DISPLAY INVISIBLE (-1555 1952);
FORCEPROP 1 LAST SIZE 1B
J 0
(-1555 1972);
DISPLAY 0.340426 (-1555 1972);
PAINT GREEN (-1555 1972);
DISPLAY INVISIBLE (-1555 1972);
FORCEPROP 2 LAST CDS_LIB mstr_symbols
J 0
(-1600 1950);
PAINT ORANGE (-1600 1950);
DISPLAY INVISIBLE (-1600 1950);
FORCEPROP 1 LAST BODY_TYPE PLUMBING
J 0
(-1645 1907);
DISPLAY 0.340426 (-1645 1907);
PAINT GREEN (-1645 1907);
DISPLAY INVISIBLE (-1645 1907);
FORCEPROP 1 LAST HDL_POWER P3V3_STBY
J 0
(-1900 1825);
DISPLAY 0.872340 (-1900 1825);
PAINT ORANGE (-1900 1825);
DISPLAY INVISIBLE (-1900 1825);
FORCEADD CAP_A..1
(-1600 1700);
FORCEPROP 1 LASTPIN (-1600 1600) $PN 2
J 0
(-1590 1580);
DISPLAY 0.617021 (-1590 1580);
PAINT ORANGE (-1590 1580);
FORCEPROP 1 LASTPIN (-1600 1800) $PN 1
J 0
(-1590 1780);
DISPLAY 0.617021 (-1590 1780);
PAINT ORANGE (-1590 1780);
FORCEPROP 1 LAST LOCATION C1R28
J 0
(-1550 1800);
DISPLAY 0.617021 (-1550 1800);
PAINT AQUA (-1550 1800);
FORCEPROP 1 LAST PART_NUMBER A36096-030
J 0
(-1550 1550);
DISPLAY 0.617021 (-1550 1550);
PAINT BLUE (-1550 1550);
FORCEPROP 1 LAST VALUE 0.1UF
J 0
(-1550 1750);
DISPLAY 0.617021 (-1550 1750);
PAINT SKYBLUE (-1550 1750);
FORCEPROP 1 LAST TOLERANCE 10%
J 0
(-1550 1650);
DISPLAY 0.617021 (-1550 1650);
PAINT SKYBLUE (-1550 1650);
FORCEPROP 1 LAST PACK_TYPE 0402V
J 0
(-1550 1500);
DISPLAY 0.617021 (-1550 1500);
PAINT SKYBLUE (-1550 1500);
FORCEPROP 1 LAST VOLTAGE 16V
J 0
(-1550 1700);
DISPLAY 0.617021 (-1550 1700);
PAINT SKYBLUE (-1550 1700);
FORCEPROP 1 LAST MATERIAL X7R
J 0
(-1550 1600);
DISPLAY 0.617021 (-1550 1600);
PAINT SKYBLUE (-1550 1600);
FORCEPROP 2 LAST CDS_LIB dev_discrete
J 0
(-1600 1700);
PAINT ORANGE (-1600 1700);
DISPLAY INVISIBLE (-1600 1700);
FORCEPROP 2 LAST ROOM FAST_PROCHOT
J 0
(-1550 1850);
DISPLAY 1.021277 (-1550 1850);
PAINT ORANGE (-1550 1850);
DISPLAY INVISIBLE (-1550 1850);
FORCEPROP 2 LAST CDS_SEC 1
J 0
(-1550 1850);
PAINT ORANGE (-1550 1850);
DISPLAY INVISIBLE (-1550 1850);
FORCEPROP 2 LAST CDS_LOCATION C1R28
J 0
(-1550 1800);
DISPLAY 0.617021 (-1550 1800);
PAINT AQUA (-1550 1800);
DISPLAY INVISIBLE (-1550 1800);
FORCEPROP 1 LAST PATH I49
J 0
(-1550 1850);
DISPLAY 0.978723 (-1550 1850);
PAINT WHITE (-1550 1850);
DISPLAY INVISIBLE (-1550 1850);
FORCEPROP 2 LAST SEC 1
J 0
(-1550 1900);
DISPLAY 0.680851 (-1550 1900);
PAINT MONO (-1550 1900);
DISPLAY INVISIBLE (-1550 1900);
FORCEPROP 2 LAST SEC_TYPE 0402V
J 0
(-1550 1900);
DISPLAY 1.021277 (-1550 1900);
PAINT ORANGE (-1550 1900);
DISPLAY INVISIBLE (-1550 1900);
FORCEPROP 2 LAST BOM_COST FAST_PROCHOT
J 0
(-1550 1900);
DISPLAY 1.021277 (-1550 1900);
PAINT ORANGE (-1550 1900);
DISPLAY INVISIBLE (-1550 1900);
FORCEADD OFFPAGE..1
(-2300 4425);
FORCEPROP 2 LAST $XR2 120 
J 0
(-2792 4425);
DISPLAY 0.638298 (-2792 4425);
PAINT MONO (-2792 4425);
FORCEPROP 2 LAST $XR1 145 
J 0
(-2672 4425);
DISPLAY 0.638298 (-2672 4425);
PAINT MONO (-2672 4425);
FORCEPROP 2 LAST $XR0 119 
J 0
(-2552 4425);
DISPLAY 0.638298 (-2552 4425);
PAINT MONO (-2552 4425);
FORCEPROP 2 LAST PATH I5
J 0
(-2250 4500);
DISPLAY 1.021277 (-2250 4500);
PAINT ORANGE (-2250 4500);
DISPLAY INVISIBLE (-2250 4500);
FORCEPROP 2 LAST CDS_LIB mstr_standard
J 0
(-2300 4425);
PAINT MONO (-2300 4425);
DISPLAY INVISIBLE (-2300 4425);
FORCEPROP 1 LAST OFFPAGE TRUE
J 0
(-1975 4300);
DISPLAY 0.872340 (-1975 4300);
PAINT GREEN (-1975 4300);
DISPLAY INVISIBLE (-1975 4300);
FORCEPROP 1 LAST COMMENT_BODY TRUE
J 0
(-2175 4325);
DISPLAY 0.872340 (-2175 4325);
PAINT GREEN (-2175 4325);
DISPLAY INVISIBLE (-2175 4325);
FORCEADD GND..1
(-1600 1425);
FORCEPROP 3 LASTPIN (-1600 1475) SIG_NAME GND\g
J 0
(-1590 1485);
DISPLAY 0.659574 (-1590 1485);
PAINT MONO (-1590 1485);
DISPLAY INVISIBLE (-1590 1485);
FORCEPROP 1 LAST VOLTAGE 0.0V
J 0
(-1645 1382);
DISPLAY 0.340426 (-1645 1382);
PAINT SKYBLUE (-1645 1382);
DISPLAY INVISIBLE (-1645 1382);
FORCEPROP 2 LAST CDS_LIB mstr_symbols
J 0
(-1600 1425);
PAINT ORANGE (-1600 1425);
DISPLAY INVISIBLE (-1600 1425);
FORCEPROP 1 LAST PATH I50
J 0
(-1525 1425);
DISPLAY 0.872340 (-1525 1425);
PAINT AQUA (-1525 1425);
DISPLAY INVISIBLE (-1525 1425);
FORCEPROP 1 LAST SIZE 1B
J 0
(-1525 1375);
DISPLAY 0.872340 (-1525 1375);
PAINT AQUA (-1525 1375);
DISPLAY INVISIBLE (-1525 1375);
FORCEPROP 1 LAST BODY_TYPE PLUMBING
J 0
(-1645 1382);
DISPLAY 0.340426 (-1645 1382);
PAINT GREEN (-1645 1382);
DISPLAY INVISIBLE (-1645 1382);
FORCEPROP 1 LAST HDL_POWER GND
J 0
(-1600 1575);
DISPLAY 0.872340 (-1600 1575);
PAINT GREEN (-1600 1575);
DISPLAY INVISIBLE (-1600 1575);
FORCEADD RES..1
(-475 2525);
FORCEPROP 1 LAST WATTAGE 1/16W
J 2
(-325 2475);
DISPLAY 0.617021 (-325 2475);
PAINT SKYBLUE (-325 2475);
FORCEPROP 1 LAST TOLERANCE 5%
J 0
(-375 2425);
DISPLAY 0.617021 (-375 2425);
PAINT SKYBLUE (-375 2425);
FORCEPROP 1 LAST LOCATION R1R8
J 0
(-525 2575);
DISPLAY 0.617021 (-525 2575);
PAINT AQUA (-525 2575);
FORCEPROP 1 LASTPIN (-575 2525) $PN 1
J 0
(-563 2537);
DISPLAY 0.617021 (-563 2537);
PAINT ORANGE (-563 2537);
FORCEPROP 1 LASTPIN (-375 2525) $PN 2
J 0
(-413 2537);
DISPLAY 0.617021 (-413 2537);
PAINT ORANGE (-413 2537);
FORCEPROP 1 LAST PACK_TYPE 0402
J 0
(-600 2425);
DISPLAY 0.617021 (-600 2425);
PAINT SKYBLUE (-600 2425);
FORCEPROP 1 LAST VALUE 0.0
J 2
(-575 2475);
DISPLAY 0.617021 (-575 2475);
PAINT SKYBLUE (-575 2475);
FORCEPROP 1 LAST MATERIAL CHIP
J 0
(-750 2425);
DISPLAY 0.617021 (-750 2425);
PAINT SKYBLUE (-750 2425);
FORCEPROP 1 LAST PART_NUMBER G21497-005
J 0
(-600 2375);
DISPLAY 0.617021 (-600 2375);
PAINT BLUE (-600 2375);
FORCEPROP 2 LAST SEC_TYPE 0402
J 0
(-525 2725);
DISPLAY 1.021277 (-525 2725);
PAINT ORANGE (-525 2725);
DISPLAY INVISIBLE (-525 2725);
FORCEPROP 2 LAST SEC 1
J 0
(-525 2725);
DISPLAY 0.680851 (-525 2725);
PAINT MONO (-525 2725);
DISPLAY INVISIBLE (-525 2725);
FORCEPROP 2 LAST CDS_LOCATION R1R8
J 0
(-525 2575);
DISPLAY 0.617021 (-525 2575);
PAINT AQUA (-525 2575);
DISPLAY INVISIBLE (-525 2575);
FORCEPROP 1 LAST PATH I51
J 0
(-525 2675);
DISPLAY 0.978723 (-525 2675);
PAINT WHITE (-525 2675);
DISPLAY INVISIBLE (-525 2675);
FORCEPROP 2 LAST BOM_COST PROC_SIDEBAND
J 2
(-475 2525);
PAINT MONO (-475 2525);
DISPLAY INVISIBLE (-475 2525);
FORCEPROP 2 LAST CDS_LIB mstr_discrete
J 0
(-475 2525);
PAINT MONO (-475 2525);
DISPLAY INVISIBLE (-475 2525);
FORCEPROP 2 LAST ROOM PROC_SIDEBAND
J 0
(-550 2450);
DISPLAY 0.617021 (-550 2450);
PAINT ORANGE (-550 2450);
DISPLAY INVISIBLE (-550 2450);
FORCEADD P3V3_STBY..1
(-3825 5475);
FORCEPROP 3 LASTPIN (-3825 5425) SIG_NAME P3V3_STBY\g
J 0
(-3815 5435);
DISPLAY 0.659574 (-3815 5435);
PAINT MONO (-3815 5435);
DISPLAY INVISIBLE (-3815 5435);
FORCEPROP 1 LAST VOLTAGE 3.3V
J 0
(-3870 5432);
DISPLAY 0.340426 (-3870 5432);
PAINT SKYBLUE (-3870 5432);
DISPLAY INVISIBLE (-3870 5432);
FORCEPROP 1 LAST SIZE 1B
J 0
(-3780 5497);
DISPLAY 0.340426 (-3780 5497);
PAINT GREEN (-3780 5497);
DISPLAY INVISIBLE (-3780 5497);
FORCEPROP 1 LAST PATH I53
J 0
(-3780 5477);
DISPLAY 0.340426 (-3780 5477);
PAINT GREEN (-3780 5477);
DISPLAY INVISIBLE (-3780 5477);
FORCEPROP 2 LAST CDS_LIB mstr_symbols
J 0
(-3825 5475);
PAINT MONO (-3825 5475);
DISPLAY INVISIBLE (-3825 5475);
FORCEPROP 1 LAST BODY_TYPE PLUMBING
J 0
(-3870 5432);
DISPLAY 0.340426 (-3870 5432);
PAINT GREEN (-3870 5432);
DISPLAY INVISIBLE (-3870 5432);
FORCEPROP 1 LAST HDL_POWER P3V3_STBY
J 0
(-4125 5350);
DISPLAY 0.872340 (-4125 5350);
PAINT ORANGE (-4125 5350);
DISPLAY INVISIBLE (-4125 5350);
FORCEADD RES..2
(-3450 2075);
FORCEPROP 1 LASTPIN (-3450 1975) $PN 2
J 0
(-3445 1985);
DISPLAY 0.617021 (-3445 1985);
PAINT ORANGE (-3445 1985);
FORCEPROP 1 LAST PART_NUMBER G21796-072
J 0
(-3410 1950);
DISPLAY 0.617021 (-3410 1950);
PAINT BLUE (-3410 1950);
FORCEPROP 1 LAST PACK_TYPE 0402
J 0
(-3410 1900);
DISPLAY 0.617021 (-3410 1900);
PAINT SKYBLUE (-3410 1900);
FORCEPROP 1 LAST MATERIAL CHIP
J 0
(-3410 2000);
DISPLAY 0.617021 (-3410 2000);
PAINT SKYBLUE (-3410 2000);
FORCEPROP 1 LAST TOLERANCE 1%
J 0
(-3405 2100);
DISPLAY 0.617021 (-3405 2100);
PAINT SKYBLUE (-3405 2100);
FORCEPROP 1 LASTPIN (-3450 2175) $PN 1
J 0
(-3445 2137);
DISPLAY 0.617021 (-3445 2137);
PAINT ORANGE (-3445 2137);
FORCEPROP 1 LAST LOCATION R2T3
J 0
(-3405 2200);
DISPLAY 0.617021 (-3405 2200);
PAINT AQUA (-3405 2200);
FORCEPROP 1 LAST VALUE 4.75K
J 0
(-3405 2150);
DISPLAY 0.617021 (-3405 2150);
PAINT SKYBLUE (-3405 2150);
FORCEPROP 1 LAST WATTAGE 1/16W
J 0
(-3410 2050);
DISPLAY 0.617021 (-3410 2050);
PAINT SKYBLUE (-3410 2050);
FORCEPROP 2 LAST CDS_LIB mstr_discrete
J 0
(-3450 2075);
PAINT MONO (-3450 2075);
DISPLAY INVISIBLE (-3450 2075);
FORCEPROP 2 LAST CDS_LOCATION R2T3
J 0
(-3405 2200);
DISPLAY 0.617021 (-3405 2200);
PAINT AQUA (-3405 2200);
DISPLAY INVISIBLE (-3405 2200);
FORCEPROP 1 LAST PATH I54
J 0
(-3400 2250);
DISPLAY 0.978723 (-3400 2250);
PAINT WHITE (-3400 2250);
DISPLAY INVISIBLE (-3400 2250);
FORCEPROP 0 LAST ROOM FAST_PROCHOT
J 0
(-3400 2300);
DISPLAY 1.021277 (-3400 2300);
PAINT ORANGE (-3400 2300);
DISPLAY INVISIBLE (-3400 2300);
FORCEPROP 2 LAST SEC 1
J 0
(-3400 2300);
DISPLAY 0.680851 (-3400 2300);
PAINT MONO (-3400 2300);
DISPLAY INVISIBLE (-3400 2300);
FORCEPROP 2 LAST SEC_TYPE 0402
J 0
(-3400 2300);
DISPLAY 1.021277 (-3400 2300);
PAINT ORANGE (-3400 2300);
DISPLAY INVISIBLE (-3400 2300);
FORCEPROP 0 LAST BOM_COST FAST_PROCHOT
J 0
(-3400 2400);
DISPLAY 1.021277 (-3400 2400);
PAINT ORANGE (-3400 2400);
DISPLAY INVISIBLE (-3400 2400);
FORCEADD P3V3_STBY..1
(-3450 2350);
FORCEPROP 3 LASTPIN (-3450 2300) SIG_NAME P3V3_STBY\g
J 0
(-3440 2310);
DISPLAY 0.659574 (-3440 2310);
PAINT MONO (-3440 2310);
DISPLAY INVISIBLE (-3440 2310);
FORCEPROP 2 LAST CDS_LIB mstr_symbols
J 0
(-3450 2350);
PAINT MONO (-3450 2350);
DISPLAY INVISIBLE (-3450 2350);
FORCEPROP 1 LAST PATH I55
J 0
(-3405 2352);
DISPLAY 0.340426 (-3405 2352);
PAINT GREEN (-3405 2352);
DISPLAY INVISIBLE (-3405 2352);
FORCEPROP 1 LAST VOLTAGE 3.3V
J 0
(-3495 2307);
DISPLAY 0.340426 (-3495 2307);
PAINT SKYBLUE (-3495 2307);
DISPLAY INVISIBLE (-3495 2307);
FORCEPROP 1 LAST SIZE 1B
J 0
(-3405 2372);
DISPLAY 0.340426 (-3405 2372);
PAINT GREEN (-3405 2372);
DISPLAY INVISIBLE (-3405 2372);
FORCEPROP 1 LAST BODY_TYPE PLUMBING
J 0
(-3495 2307);
DISPLAY 0.340426 (-3495 2307);
PAINT GREEN (-3495 2307);
DISPLAY INVISIBLE (-3495 2307);
FORCEPROP 1 LAST HDL_POWER P3V3_STBY
J 0
(-3750 2225);
DISPLAY 0.872340 (-3750 2225);
PAINT ORANGE (-3750 2225);
DISPLAY INVISIBLE (-3750 2225);
FORCEADD RES..2
(-4150 5100);
FORCEPROP 1 LAST TOLERANCE 1%
J 0
(-4105 5125);
DISPLAY 0.617021 (-4105 5125);
PAINT SKYBLUE (-4105 5125);
FORCEPROP 1 LAST WATTAGE 1/16W
J 0
(-4110 5075);
DISPLAY 0.617021 (-4110 5075);
PAINT SKYBLUE (-4110 5075);
FORCEPROP 1 LAST MATERIAL CHIP
J 0
(-4110 5025);
DISPLAY 0.617021 (-4110 5025);
PAINT SKYBLUE (-4110 5025);
FORCEPROP 1 LAST PACK_TYPE 0402
J 0
(-4110 4925);
DISPLAY 0.617021 (-4110 4925);
PAINT SKYBLUE (-4110 4925);
FORCEPROP 1 LASTPIN (-4150 5200) $PN 1
J 0
(-4145 5162);
DISPLAY 0.617021 (-4145 5162);
PAINT ORANGE (-4145 5162);
FORCEPROP 1 LASTPIN (-4150 5000) $PN 2
J 0
(-4145 5010);
DISPLAY 0.617021 (-4145 5010);
PAINT ORANGE (-4145 5010);
FORCEPROP 1 LAST VALUE 4.75K
J 0
(-4105 5175);
DISPLAY 0.617021 (-4105 5175);
PAINT SKYBLUE (-4105 5175);
FORCEPROP 1 LAST LOCATION R2P5
J 0
(-4105 5225);
DISPLAY 0.617021 (-4105 5225);
PAINT AQUA (-4105 5225);
FORCEPROP 1 LAST PART_NUMBER G21796-072
J 0
(-4110 4975);
DISPLAY 0.617021 (-4110 4975);
PAINT BLUE (-4110 4975);
FORCEPROP 1 LAST PATH I56
J 0
(-4100 5275);
DISPLAY 0.978723 (-4100 5275);
PAINT WHITE (-4100 5275);
DISPLAY INVISIBLE (-4100 5275);
FORCEPROP 2 LAST CDS_LOCATION R2P5
J 0
(-4105 5225);
DISPLAY 0.617021 (-4105 5225);
PAINT AQUA (-4105 5225);
DISPLAY INVISIBLE (-4105 5225);
FORCEPROP 0 LAST BOM_COST PROC_SIDEBAND
J 0
(-4100 5325);
DISPLAY 1.021277 (-4100 5325);
PAINT ORANGE (-4100 5325);
DISPLAY INVISIBLE (-4100 5325);
FORCEPROP 2 LAST SEC_TYPE 0402
J 0
(-4100 5325);
DISPLAY 1.021277 (-4100 5325);
PAINT ORANGE (-4100 5325);
DISPLAY INVISIBLE (-4100 5325);
FORCEPROP 2 LAST SEC 1
J 0
(-4100 5325);
DISPLAY 0.680851 (-4100 5325);
PAINT MONO (-4100 5325);
DISPLAY INVISIBLE (-4100 5325);
FORCEPROP 0 LAST ROOM PROC_SIDEBAND
J 0
(-4100 5325);
DISPLAY 1.021277 (-4100 5325);
PAINT ORANGE (-4100 5325);
DISPLAY INVISIBLE (-4100 5325);
FORCEPROP 2 LAST CDS_LIB mstr_discrete
J 0
(-4150 5100);
PAINT MONO (-4150 5100);
DISPLAY INVISIBLE (-4150 5100);
FORCEADD FET_N..8
(-4150 4225);
FORCEPROP 1 LAST MATERIAL FET
J 0
(-3950 4125);
DISPLAY 0.617021 (-3950 4125);
PAINT SKYBLUE (-3950 4125);
FORCEPROP 1 LAST PART_NUMBER C79254-001
J 0
(-3950 4025);
DISPLAY 0.617021 (-3950 4025);
PAINT BLUE (-3950 4025);
FORCEPROP 1 LASTPIN (-4150 4025) $PN 2
J 2
(-4092 4025);
DISPLAY 0.617021 (-4092 4025);
PAINT WHITE (-4092 4025);
FORCEPROP 1 LAST VALUE 2N7002
J 0
(-3950 4175);
DISPLAY 0.617021 (-3950 4175);
PAINT SKYBLUE (-3950 4175);
FORCEPROP 1 LASTPIN (-4350 4125) $PN 1
J 2
(-4347 4140);
DISPLAY 0.617021 (-4347 4140);
PAINT WHITE (-4347 4140);
FORCEPROP 1 LASTPIN (-4150 4425) $PN 3
J 2
(-4097 4390);
DISPLAY 0.617021 (-4097 4390);
PAINT WHITE (-4097 4390);
FORCEPROP 1 LAST LOCATION Q2P1
J 0
(-3950 4225);
DISPLAY 0.617021 (-3950 4225);
PAINT AQUA (-3950 4225);
FORCEPROP 2 LAST CDS_LIB mstr_discrete
J 0
(-4150 4225);
PAINT MONO (-4150 4225);
DISPLAY INVISIBLE (-4150 4225);
FORCEPROP 1 LAST PACK_TYPE SOT23LF
J 0
(-3950 4075);
DISPLAY 0.978723 (-3950 4075);
PAINT SKYBLUE (-3950 4075);
DISPLAY INVISIBLE (-3950 4075);
FORCEPROP 0 LAST ROOM PROC_SIDEBAND
J 0
(-3950 4325);
DISPLAY 1.021277 (-3950 4325);
PAINT ORANGE (-3950 4325);
DISPLAY INVISIBLE (-3950 4325);
FORCEPROP 1 LAST PATH I58
J 0
(-3950 4275);
DISPLAY 0.978723 (-3950 4275);
PAINT BLUE (-3950 4275);
DISPLAY INVISIBLE (-3950 4275);
FORCEPROP 2 LAST CDS_LOCATION Q2P1
J 0
(-3950 4225);
DISPLAY 0.617021 (-3950 4225);
PAINT AQUA (-3950 4225);
DISPLAY INVISIBLE (-3950 4225);
FORCEPROP 2 LAST SEC 1
J 0
(-3950 4325);
DISPLAY 0.680851 (-3950 4325);
PAINT MONO (-3950 4325);
DISPLAY INVISIBLE (-3950 4325);
FORCEPROP 0 LAST BOM_COST PROC_SIDEBAND
J 0
(-3950 4425);
DISPLAY 1.021277 (-3950 4425);
PAINT ORANGE (-3950 4425);
DISPLAY INVISIBLE (-3950 4425);
FORCEPROP 2 LAST SEC_TYPE SOT23LF
J 0
(-3950 4325);
DISPLAY 1.021277 (-3950 4325);
PAINT ORANGE (-3950 4325);
DISPLAY INVISIBLE (-3950 4325);
FORCEADD OFFPAGE..1
(-5000 4125);
FORCEPROP 2 LAST $XR1 145 
J 0
(-5372 4125);
DISPLAY 0.638298 (-5372 4125);
PAINT MONO (-5372 4125);
FORCEPROP 2 LAST $XR0 119 
J 0
(-5252 4125);
DISPLAY 0.638298 (-5252 4125);
PAINT MONO (-5252 4125);
FORCEPROP 2 LAST CDS_LIB mstr_standard
J 0
(-5000 4125);
PAINT MONO (-5000 4125);
DISPLAY INVISIBLE (-5000 4125);
FORCEPROP 2 LAST PATH I59
J 0
(-4950 4200);
DISPLAY 1.021277 (-4950 4200);
PAINT ORANGE (-4950 4200);
DISPLAY INVISIBLE (-4950 4200);
FORCEPROP 1 LAST OFFPAGE TRUE
J 0
(-4675 4000);
DISPLAY 0.872340 (-4675 4000);
PAINT GREEN (-4675 4000);
DISPLAY INVISIBLE (-4675 4000);
FORCEPROP 1 LAST COMMENT_BODY TRUE
J 0
(-4875 4025);
DISPLAY 0.872340 (-4875 4025);
PAINT GREEN (-4875 4025);
DISPLAY INVISIBLE (-4875 4025);
FORCEADD P3V3_STBY..1
(-5100 3600);
FORCEPROP 3 LASTPIN (-5100 3550) SIG_NAME P3V3_STBY\g
J 0
(-5090 3560);
DISPLAY 0.659574 (-5090 3560);
PAINT MONO (-5090 3560);
DISPLAY INVISIBLE (-5090 3560);
FORCEPROP 1 LAST VOLTAGE 3.3V
J 0
(-5145 3557);
DISPLAY 0.340426 (-5145 3557);
PAINT SKYBLUE (-5145 3557);
DISPLAY INVISIBLE (-5145 3557);
FORCEPROP 1 LAST PATH I6
J 0
(-5055 3602);
DISPLAY 0.340426 (-5055 3602);
PAINT GREEN (-5055 3602);
DISPLAY INVISIBLE (-5055 3602);
FORCEPROP 1 LAST SIZE 1B
J 0
(-5055 3622);
DISPLAY 0.340426 (-5055 3622);
PAINT GREEN (-5055 3622);
DISPLAY INVISIBLE (-5055 3622);
FORCEPROP 2 LAST CDS_LIB mstr_symbols
J 0
(-5100 3600);
PAINT ORANGE (-5100 3600);
DISPLAY INVISIBLE (-5100 3600);
FORCEPROP 1 LAST BODY_TYPE PLUMBING
J 0
(-5145 3557);
DISPLAY 0.340426 (-5145 3557);
PAINT GREEN (-5145 3557);
DISPLAY INVISIBLE (-5145 3557);
FORCEPROP 1 LAST HDL_POWER P3V3_STBY
J 0
(-5400 3475);
DISPLAY 0.872340 (-5400 3475);
PAINT ORANGE (-5400 3475);
DISPLAY INVISIBLE (-5400 3475);
FORCEADD GND..1
(-4150 3900);
FORCEPROP 3 LASTPIN (-4150 3950) SIG_NAME GND\g
J 0
(-4140 3960);
DISPLAY 0.659574 (-4140 3960);
PAINT MONO (-4140 3960);
DISPLAY INVISIBLE (-4140 3960);
FORCEPROP 1 LAST VOLTAGE 0.0V
J 0
(-4195 3857);
DISPLAY 0.340426 (-4195 3857);
PAINT SKYBLUE (-4195 3857);
DISPLAY INVISIBLE (-4195 3857);
FORCEPROP 2 LAST CDS_LIB mstr_symbols
J 0
(-4150 3900);
PAINT MONO (-4150 3900);
DISPLAY INVISIBLE (-4150 3900);
FORCEPROP 1 LAST SIZE 1B
J 0
(-4075 3850);
DISPLAY 0.872340 (-4075 3850);
PAINT AQUA (-4075 3850);
DISPLAY INVISIBLE (-4075 3850);
FORCEPROP 1 LAST PATH I60
J 0
(-4075 3900);
DISPLAY 0.872340 (-4075 3900);
PAINT AQUA (-4075 3900);
DISPLAY INVISIBLE (-4075 3900);
FORCEPROP 1 LAST BODY_TYPE PLUMBING
J 0
(-4195 3857);
DISPLAY 0.340426 (-4195 3857);
PAINT GREEN (-4195 3857);
DISPLAY INVISIBLE (-4195 3857);
FORCEPROP 1 LAST HDL_POWER GND
J 0
(-4150 4050);
DISPLAY 0.872340 (-4150 4050);
PAINT GREEN (-4150 4050);
DISPLAY INVISIBLE (-4150 4050);
FORCEADD RES..2
(-4600 4350);
FORCEPROP 1 LASTPIN (-4600 4250) $PN 2
J 0
(-4595 4260);
DISPLAY 0.617021 (-4595 4260);
PAINT ORANGE (-4595 4260);
FORCEPROP 1 LAST PACK_TYPE 0402
J 0
(-4560 4175);
DISPLAY 0.617021 (-4560 4175);
PAINT SKYBLUE (-4560 4175);
FORCEPROP 1 LAST MATERIAL CHIP
J 0
(-4560 4275);
DISPLAY 0.617021 (-4560 4275);
PAINT SKYBLUE (-4560 4275);
FORCEPROP 1 LAST WATTAGE 1/16W
J 0
(-4560 4325);
DISPLAY 0.617021 (-4560 4325);
PAINT SKYBLUE (-4560 4325);
FORCEPROP 1 LAST TOLERANCE 1%
J 0
(-4555 4375);
DISPLAY 0.617021 (-4555 4375);
PAINT SKYBLUE (-4555 4375);
FORCEPROP 1 LASTPIN (-4600 4450) $PN 1
J 0
(-4595 4412);
DISPLAY 0.617021 (-4595 4412);
PAINT ORANGE (-4595 4412);
FORCEPROP 1 LAST LOCATION R2P13
J 0
(-4555 4475);
DISPLAY 0.617021 (-4555 4475);
PAINT AQUA (-4555 4475);
FORCEPROP 1 LAST VALUE 4.75K
J 0
(-4555 4425);
DISPLAY 0.617021 (-4555 4425);
PAINT SKYBLUE (-4555 4425);
FORCEPROP 1 LAST PART_NUMBER G21796-072
J 0
(-4560 4225);
DISPLAY 0.617021 (-4560 4225);
PAINT BLUE (-4560 4225);
FORCEPROP 2 LAST CDS_LIB mstr_discrete
J 0
(-4600 4350);
PAINT MONO (-4600 4350);
DISPLAY INVISIBLE (-4600 4350);
FORCEPROP 2 LAST CDS_LOCATION R2P13
J 0
(-4555 4475);
DISPLAY 0.617021 (-4555 4475);
PAINT AQUA (-4555 4475);
DISPLAY INVISIBLE (-4555 4475);
FORCEPROP 1 LAST PATH I61
J 0
(-4550 4525);
DISPLAY 0.978723 (-4550 4525);
PAINT WHITE (-4550 4525);
DISPLAY INVISIBLE (-4550 4525);
FORCEPROP 2 LAST SEC 1
J 0
(-4550 4575);
DISPLAY 0.680851 (-4550 4575);
PAINT MONO (-4550 4575);
DISPLAY INVISIBLE (-4550 4575);
FORCEPROP 0 LAST ROOM PROC_SIDEBAND
J 0
(-4550 4575);
DISPLAY 1.021277 (-4550 4575);
PAINT ORANGE (-4550 4575);
DISPLAY INVISIBLE (-4550 4575);
FORCEPROP 2 LAST SEC_TYPE 0402
J 0
(-4550 4575);
DISPLAY 1.021277 (-4550 4575);
PAINT ORANGE (-4550 4575);
DISPLAY INVISIBLE (-4550 4575);
FORCEPROP 0 LAST BOM_COST PROC_SIDEBAND
J 0
(-4550 4675);
DISPLAY 1.021277 (-4550 4675);
PAINT ORANGE (-4550 4675);
DISPLAY INVISIBLE (-4550 4675);
FORCEADD P3V3_STBY..1
(-4600 4575);
FORCEPROP 3 LASTPIN (-4600 4525) SIG_NAME P3V3_STBY\g
J 0
(-4590 4535);
DISPLAY 0.659574 (-4590 4535);
PAINT MONO (-4590 4535);
DISPLAY INVISIBLE (-4590 4535);
FORCEPROP 1 LAST VOLTAGE 3.3V
J 0
(-4645 4532);
DISPLAY 0.340426 (-4645 4532);
PAINT SKYBLUE (-4645 4532);
DISPLAY INVISIBLE (-4645 4532);
FORCEPROP 1 LAST PATH I62
J 0
(-4555 4577);
DISPLAY 0.340426 (-4555 4577);
PAINT GREEN (-4555 4577);
DISPLAY INVISIBLE (-4555 4577);
FORCEPROP 2 LAST CDS_LIB mstr_symbols
J 0
(-4600 4575);
PAINT MONO (-4600 4575);
DISPLAY INVISIBLE (-4600 4575);
FORCEPROP 1 LAST SIZE 1B
J 0
(-4555 4597);
DISPLAY 0.340426 (-4555 4597);
PAINT GREEN (-4555 4597);
DISPLAY INVISIBLE (-4555 4597);
FORCEPROP 1 LAST BODY_TYPE PLUMBING
J 0
(-4645 4532);
DISPLAY 0.340426 (-4645 4532);
PAINT GREEN (-4645 4532);
DISPLAY INVISIBLE (-4645 4532);
FORCEPROP 1 LAST HDL_POWER P3V3_STBY
J 0
(-4900 4450);
DISPLAY 0.872340 (-4900 4450);
PAINT ORANGE (-4900 4450);
DISPLAY INVISIBLE (-4900 4450);
FORCEADD RES..2
(-4525 3925);
FORCEPROP 1 LAST VALUE 1.00K
J 0
(-4480 4000);
DISPLAY 0.617021 (-4480 4000);
PAINT SKYBLUE (-4480 4000);
FORCEPROP 1 LASTPIN (-4525 3825) $PN 2
J 0
(-4520 3835);
DISPLAY 0.787234 (-4520 3835);
PAINT ORANGE (-4520 3835);
FORCEPROP 1 LASTPIN (-4525 4025) $PN 1
J 0
(-4520 3987);
DISPLAY 0.787234 (-4520 3987);
PAINT ORANGE (-4520 3987);
FORCEPROP 1 LAST PACK_TYPE 0402
J 0
(-4485 3750);
DISPLAY 0.617021 (-4485 3750);
PAINT SKYBLUE (-4485 3750);
FORCEPROP 1 LAST MATERIAL EMPTY
J 0
(-4485 3850);
DISPLAY 0.617021 (-4485 3850);
PAINT RED (-4485 3850);
FORCEPROP 1 LAST PART_NUMBER G21796-026
J 0
(-4485 3800);
DISPLAY 0.617021 (-4485 3800);
PAINT BLUE (-4485 3800);
FORCEPROP 1 LAST TOLERANCE 1%
J 0
(-4480 3950);
DISPLAY 0.617021 (-4480 3950);
PAINT SKYBLUE (-4480 3950);
FORCEPROP 1 LAST LOCATION R2P11
J 0
(-4480 4050);
DISPLAY 0.617021 (-4480 4050);
PAINT AQUA (-4480 4050);
FORCEPROP 1 LAST WATTAGE 1/16W
J 0
(-4485 3900);
DISPLAY 0.617021 (-4485 3900);
PAINT SKYBLUE (-4485 3900);
FORCEPROP 2 LAST SEC_TYPE 0402
J 0
(-4475 4150);
DISPLAY 1.021277 (-4475 4150);
PAINT ORANGE (-4475 4150);
DISPLAY INVISIBLE (-4475 4150);
FORCEPROP 2 LAST SEC 1
J 0
(-4475 4150);
PAINT MONO (-4475 4150);
DISPLAY INVISIBLE (-4475 4150);
FORCEPROP 2 LAST CDS_LIB mstr_discrete
J 0
(-4525 3925);
PAINT MONO (-4525 3925);
DISPLAY INVISIBLE (-4525 3925);
FORCEPROP 2 LAST CDS_LOCATION R2P11
J 0
(-4480 4050);
DISPLAY 0.617021 (-4480 4050);
PAINT AQUA (-4480 4050);
DISPLAY INVISIBLE (-4480 4050);
FORCEPROP 0 LAST ROOM PROC_SIDEBAND
J 0
(-4475 4150);
DISPLAY 1.021277 (-4475 4150);
PAINT ORANGE (-4475 4150);
DISPLAY INVISIBLE (-4475 4150);
FORCEPROP 1 LAST PATH I63
J 0
(-4475 4100);
DISPLAY 0.978723 (-4475 4100);
PAINT WHITE (-4475 4100);
DISPLAY INVISIBLE (-4475 4100);
FORCEPROP 0 LAST BOM_COST PROC_SIDEBAND
J 0
(-4475 4250);
DISPLAY 1.021277 (-4475 4250);
PAINT ORANGE (-4475 4250);
DISPLAY INVISIBLE (-4475 4250);
FORCEADD GND..1
(-4525 3700);
FORCEPROP 3 LASTPIN (-4525 3750) SIG_NAME GND\g
J 0
(-4515 3760);
DISPLAY 0.659574 (-4515 3760);
PAINT MONO (-4515 3760);
DISPLAY INVISIBLE (-4515 3760);
FORCEPROP 1 LAST VOLTAGE 0.0V
J 0
(-4570 3657);
DISPLAY 0.340426 (-4570 3657);
PAINT SKYBLUE (-4570 3657);
DISPLAY INVISIBLE (-4570 3657);
FORCEPROP 2 LAST CDS_LIB mstr_symbols
J 0
(-4525 3700);
PAINT MONO (-4525 3700);
DISPLAY INVISIBLE (-4525 3700);
FORCEPROP 1 LAST PATH I64
J 0
(-4450 3700);
DISPLAY 0.872340 (-4450 3700);
PAINT AQUA (-4450 3700);
DISPLAY INVISIBLE (-4450 3700);
FORCEPROP 1 LAST SIZE 1B
J 0
(-4450 3650);
DISPLAY 0.872340 (-4450 3650);
PAINT AQUA (-4450 3650);
DISPLAY INVISIBLE (-4450 3650);
FORCEPROP 1 LAST BODY_TYPE PLUMBING
J 0
(-4570 3657);
DISPLAY 0.340426 (-4570 3657);
PAINT GREEN (-4570 3657);
DISPLAY INVISIBLE (-4570 3657);
FORCEPROP 1 LAST HDL_POWER GND
J 0
(-4525 3850);
DISPLAY 0.872340 (-4525 3850);
PAINT GREEN (-4525 3850);
DISPLAY INVISIBLE (-4525 3850);
FORCEADD RES..2
(-2950 2775);
FORCEPROP 1 LASTPIN (-2950 2675) $PN 2
J 0
(-2945 2685);
DISPLAY 0.617021 (-2945 2685);
PAINT ORANGE (-2945 2685);
FORCEPROP 1 LAST TOLERANCE 1%
J 0
(-2905 2800);
DISPLAY 0.617021 (-2905 2800);
PAINT SKYBLUE (-2905 2800);
FORCEPROP 1 LASTPIN (-2950 2875) $PN 1
J 0
(-2945 2837);
DISPLAY 0.617021 (-2945 2837);
PAINT ORANGE (-2945 2837);
FORCEPROP 1 LAST LOCATION R9F3
J 0
(-2905 2900);
DISPLAY 0.617021 (-2905 2900);
PAINT AQUA (-2905 2900);
FORCEPROP 1 LAST PART_NUMBER G21796-072
J 0
(-2910 2650);
DISPLAY 0.617021 (-2910 2650);
PAINT BLUE (-2910 2650);
FORCEPROP 1 LAST VALUE 4.75K
J 0
(-2905 2850);
DISPLAY 0.617021 (-2905 2850);
PAINT SKYBLUE (-2905 2850);
FORCEPROP 1 LAST PACK_TYPE 0402
J 0
(-2910 2600);
DISPLAY 0.617021 (-2910 2600);
PAINT SKYBLUE (-2910 2600);
FORCEPROP 1 LAST MATERIAL CHIP
J 0
(-2910 2700);
DISPLAY 0.617021 (-2910 2700);
PAINT SKYBLUE (-2910 2700);
FORCEPROP 1 LAST WATTAGE 1/16W
J 0
(-2910 2750);
DISPLAY 0.617021 (-2910 2750);
PAINT SKYBLUE (-2910 2750);
FORCEPROP 2 LAST CDS_LIB mstr_discrete
J 0
(-2950 2775);
PAINT MONO (-2950 2775);
DISPLAY INVISIBLE (-2950 2775);
FORCEPROP 1 LAST PATH I65
J 0
(-2900 2950);
DISPLAY 0.978723 (-2900 2950);
PAINT WHITE (-2900 2950);
DISPLAY INVISIBLE (-2900 2950);
FORCEPROP 2 LAST SEC 1
J 0
(-2900 3000);
DISPLAY 0.680851 (-2900 3000);
PAINT MONO (-2900 3000);
DISPLAY INVISIBLE (-2900 3000);
FORCEPROP 2 LAST CDS_LOCATION R9F3
J 0
(-2905 2900);
DISPLAY 0.617021 (-2905 2900);
PAINT AQUA (-2905 2900);
DISPLAY INVISIBLE (-2905 2900);
FORCEPROP 0 LAST ROOM PROC_SIDEBAND
J 0
(-2900 3000);
DISPLAY 1.021277 (-2900 3000);
PAINT ORANGE (-2900 3000);
DISPLAY INVISIBLE (-2900 3000);
FORCEPROP 0 LAST BOM_COST PROC_SIDEBAND
J 0
(-2900 3000);
DISPLAY 1.021277 (-2900 3000);
PAINT ORANGE (-2900 3000);
DISPLAY INVISIBLE (-2900 3000);
FORCEPROP 2 LAST SEC_TYPE 0402
J 0
(-2900 3000);
DISPLAY 1.021277 (-2900 3000);
PAINT ORANGE (-2900 3000);
DISPLAY INVISIBLE (-2900 3000);
FORCEADD P3V3_STBY..1
(-2950 3000);
FORCEPROP 3 LASTPIN (-2950 2950) SIG_NAME P3V3_STBY\g
J 0
(-2940 2960);
DISPLAY 0.659574 (-2940 2960);
PAINT MONO (-2940 2960);
DISPLAY INVISIBLE (-2940 2960);
FORCEPROP 1 LAST VOLTAGE 3.3V
J 0
(-2995 2957);
DISPLAY 0.340426 (-2995 2957);
PAINT SKYBLUE (-2995 2957);
DISPLAY INVISIBLE (-2995 2957);
FORCEPROP 2 LAST CDS_LIB mstr_symbols
J 0
(-2950 3000);
PAINT MONO (-2950 3000);
DISPLAY INVISIBLE (-2950 3000);
FORCEPROP 1 LAST SIZE 1B
J 0
(-2905 3022);
DISPLAY 0.340426 (-2905 3022);
PAINT GREEN (-2905 3022);
DISPLAY INVISIBLE (-2905 3022);
FORCEPROP 1 LAST PATH I66
J 0
(-2905 3002);
DISPLAY 0.340426 (-2905 3002);
PAINT GREEN (-2905 3002);
DISPLAY INVISIBLE (-2905 3002);
FORCEPROP 1 LAST BODY_TYPE PLUMBING
J 0
(-2995 2957);
DISPLAY 0.340426 (-2995 2957);
PAINT GREEN (-2995 2957);
DISPLAY INVISIBLE (-2995 2957);
FORCEPROP 1 LAST HDL_POWER P3V3_STBY
J 0
(-3250 2875);
DISPLAY 0.872340 (-3250 2875);
PAINT ORANGE (-3250 2875);
DISPLAY INVISIBLE (-3250 2875);
FORCEADD FET_N..8
(-2950 1900);
FORCEPROP 1 LAST LOCATION Q8F2
J 0
(-2750 1900);
DISPLAY 0.617021 (-2750 1900);
PAINT AQUA (-2750 1900);
FORCEPROP 1 LASTPIN (-3150 1800) $PN 1
J 2
(-3147 1815);
DISPLAY 0.617021 (-3147 1815);
PAINT WHITE (-3147 1815);
FORCEPROP 1 LASTPIN (-2950 1700) $PN 2
J 2
(-2892 1700);
DISPLAY 0.617021 (-2892 1700);
PAINT WHITE (-2892 1700);
FORCEPROP 1 LAST VALUE 2N7002
J 0
(-2750 1850);
DISPLAY 0.617021 (-2750 1850);
PAINT SKYBLUE (-2750 1850);
FORCEPROP 1 LAST MATERIAL FET
J 0
(-2750 1800);
DISPLAY 0.617021 (-2750 1800);
PAINT SKYBLUE (-2750 1800);
FORCEPROP 1 LAST PART_NUMBER C79254-001
J 0
(-2750 1700);
DISPLAY 0.617021 (-2750 1700);
PAINT BLUE (-2750 1700);
FORCEPROP 1 LASTPIN (-2950 2100) $PN 3
J 2
(-2897 2065);
DISPLAY 0.617021 (-2897 2065);
PAINT WHITE (-2897 2065);
FORCEPROP 2 LAST CDS_LIB mstr_discrete
J 0
(-2950 1900);
PAINT MONO (-2950 1900);
DISPLAY INVISIBLE (-2950 1900);
FORCEPROP 1 LAST PACK_TYPE SOT23LF
J 0
(-2750 1750);
DISPLAY 0.978723 (-2750 1750);
PAINT SKYBLUE (-2750 1750);
DISPLAY INVISIBLE (-2750 1750);
FORCEPROP 0 LAST ROOM PROC_SIDEBAND
J 0
(-2750 2000);
DISPLAY 1.021277 (-2750 2000);
PAINT ORANGE (-2750 2000);
DISPLAY INVISIBLE (-2750 2000);
FORCEPROP 1 LAST PATH I67
J 0
(-2750 1950);
DISPLAY 0.978723 (-2750 1950);
PAINT BLUE (-2750 1950);
DISPLAY INVISIBLE (-2750 1950);
FORCEPROP 2 LAST CDS_LOCATION Q8F2
J 0
(-2750 1900);
DISPLAY 0.617021 (-2750 1900);
PAINT AQUA (-2750 1900);
DISPLAY INVISIBLE (-2750 1900);
FORCEPROP 2 LAST SEC 1
J 0
(-2750 2000);
DISPLAY 0.680851 (-2750 2000);
PAINT MONO (-2750 2000);
DISPLAY INVISIBLE (-2750 2000);
FORCEPROP 2 LAST SEC_TYPE SOT23LF
J 0
(-2750 2000);
DISPLAY 1.021277 (-2750 2000);
PAINT ORANGE (-2750 2000);
DISPLAY INVISIBLE (-2750 2000);
FORCEPROP 0 LAST BOM_COST PROC_SIDEBAND
J 0
(-2750 2100);
DISPLAY 1.021277 (-2750 2100);
PAINT ORANGE (-2750 2100);
DISPLAY INVISIBLE (-2750 2100);
FORCEADD GND..1
(-2950 1575);
FORCEPROP 3 LASTPIN (-2950 1625) SIG_NAME GND\g
J 0
(-2940 1635);
DISPLAY 0.659574 (-2940 1635);
PAINT MONO (-2940 1635);
DISPLAY INVISIBLE (-2940 1635);
FORCEPROP 1 LAST VOLTAGE 0.0V
J 0
(-2995 1532);
DISPLAY 0.340426 (-2995 1532);
PAINT SKYBLUE (-2995 1532);
DISPLAY INVISIBLE (-2995 1532);
FORCEPROP 1 LAST SIZE 1B
J 0
(-2875 1525);
DISPLAY 0.872340 (-2875 1525);
PAINT AQUA (-2875 1525);
DISPLAY INVISIBLE (-2875 1525);
FORCEPROP 2 LAST CDS_LIB mstr_symbols
J 0
(-2950 1575);
PAINT MONO (-2950 1575);
DISPLAY INVISIBLE (-2950 1575);
FORCEPROP 1 LAST PATH I68
J 0
(-2875 1575);
DISPLAY 0.872340 (-2875 1575);
PAINT AQUA (-2875 1575);
DISPLAY INVISIBLE (-2875 1575);
FORCEPROP 1 LAST BODY_TYPE PLUMBING
J 0
(-2995 1532);
DISPLAY 0.340426 (-2995 1532);
PAINT GREEN (-2995 1532);
DISPLAY INVISIBLE (-2995 1532);
FORCEPROP 1 LAST HDL_POWER GND
J 0
(-2950 1725);
DISPLAY 0.872340 (-2950 1725);
PAINT GREEN (-2950 1725);
DISPLAY INVISIBLE (-2950 1725);
FORCEADD OFFPAGE..1
(-4000 1800);
FORCEPROP 2 LAST $XR1 147 
J 0
(-4372 1800);
DISPLAY 0.638298 (-4372 1800);
PAINT MONO (-4372 1800);
FORCEPROP 2 LAST $XR0 119 
J 0
(-4252 1800);
DISPLAY 0.638298 (-4252 1800);
PAINT MONO (-4252 1800);
FORCEPROP 2 LAST CDS_LIB mstr_standard
J 0
(-4000 1800);
PAINT MONO (-4000 1800);
DISPLAY INVISIBLE (-4000 1800);
FORCEPROP 2 LAST PATH I69
J 0
(-3950 1875);
DISPLAY 1.021277 (-3950 1875);
PAINT ORANGE (-3950 1875);
DISPLAY INVISIBLE (-3950 1875);
FORCEPROP 1 LAST OFFPAGE TRUE
J 0
(-3675 1675);
DISPLAY 0.872340 (-3675 1675);
PAINT GREEN (-3675 1675);
DISPLAY INVISIBLE (-3675 1675);
FORCEPROP 1 LAST COMMENT_BODY TRUE
J 0
(-3875 1700);
DISPLAY 0.872340 (-3875 1700);
PAINT GREEN (-3875 1700);
DISPLAY INVISIBLE (-3875 1700);
FORCEADD GND..1
(-5100 3075);
FORCEPROP 3 LASTPIN (-5100 3125) SIG_NAME GND\g
J 0
(-5090 3135);
DISPLAY 0.659574 (-5090 3135);
PAINT MONO (-5090 3135);
DISPLAY INVISIBLE (-5090 3135);
FORCEPROP 1 LAST VOLTAGE 0.0V
J 0
(-5145 3032);
DISPLAY 0.340426 (-5145 3032);
PAINT SKYBLUE (-5145 3032);
DISPLAY INVISIBLE (-5145 3032);
FORCEPROP 1 LAST SIZE 1B
J 0
(-5025 3025);
DISPLAY 0.872340 (-5025 3025);
PAINT AQUA (-5025 3025);
DISPLAY INVISIBLE (-5025 3025);
FORCEPROP 2 LAST CDS_LIB mstr_symbols
J 0
(-5100 3075);
PAINT ORANGE (-5100 3075);
DISPLAY INVISIBLE (-5100 3075);
FORCEPROP 1 LAST PATH I7
J 0
(-5025 3075);
DISPLAY 0.872340 (-5025 3075);
PAINT AQUA (-5025 3075);
DISPLAY INVISIBLE (-5025 3075);
FORCEPROP 1 LAST BODY_TYPE PLUMBING
J 0
(-5145 3032);
DISPLAY 0.340426 (-5145 3032);
PAINT GREEN (-5145 3032);
DISPLAY INVISIBLE (-5145 3032);
FORCEPROP 1 LAST HDL_POWER GND
J 0
(-5100 3225);
DISPLAY 0.872340 (-5100 3225);
PAINT GREEN (-5100 3225);
DISPLAY INVISIBLE (-5100 3225);
FORCEADD P3V3_STBY..1
(-3150 5475);
FORCEPROP 3 LASTPIN (-3150 5425) SIG_NAME P3V3_STBY\g
J 0
(-3140 5435);
DISPLAY 0.659574 (-3140 5435);
PAINT MONO (-3140 5435);
DISPLAY INVISIBLE (-3140 5435);
FORCEPROP 1 LAST PATH I70
J 0
(-3105 5477);
DISPLAY 0.340426 (-3105 5477);
PAINT GREEN (-3105 5477);
DISPLAY INVISIBLE (-3105 5477);
FORCEPROP 2 LAST CDS_LIB mstr_symbols
J 0
(-3150 5475);
PAINT ORANGE (-3150 5475);
DISPLAY INVISIBLE (-3150 5475);
FORCEPROP 1 LAST SIZE 1B
J 0
(-3105 5497);
DISPLAY 0.340426 (-3105 5497);
PAINT GREEN (-3105 5497);
DISPLAY INVISIBLE (-3105 5497);
FORCEPROP 1 LAST VOLTAGE 3.3V
J 0
(-3195 5432);
DISPLAY 0.340426 (-3195 5432);
PAINT SKYBLUE (-3195 5432);
DISPLAY INVISIBLE (-3195 5432);
FORCEPROP 1 LAST BODY_TYPE PLUMBING
J 0
(-3195 5432);
DISPLAY 0.340426 (-3195 5432);
PAINT GREEN (-3195 5432);
DISPLAY INVISIBLE (-3195 5432);
FORCEPROP 1 LAST HDL_POWER P3V3_STBY
J 0
(-3450 5350);
DISPLAY 0.872340 (-3450 5350);
PAINT ORANGE (-3450 5350);
DISPLAY INVISIBLE (-3450 5350);
FORCEADD RES..2
(-3150 5100);
FORCEPROP 1 LAST PART_NUMBER G21796-072
J 0
(-3110 4975);
DISPLAY 0.617021 (-3110 4975);
PAINT BLUE (-3110 4975);
FORCEPROP 1 LASTPIN (-3150 5000) $PN 2
J 0
(-3145 5010);
DISPLAY 0.617021 (-3145 5010);
PAINT ORANGE (-3145 5010);
FORCEPROP 1 LASTPIN (-3150 5200) $PN 1
J 0
(-3145 5162);
DISPLAY 0.617021 (-3145 5162);
PAINT ORANGE (-3145 5162);
FORCEPROP 1 LAST PACK_TYPE 0402
J 0
(-3110 4925);
DISPLAY 0.617021 (-3110 4925);
PAINT SKYBLUE (-3110 4925);
FORCEPROP 1 LAST MATERIAL CHIP
J 0
(-3110 5025);
DISPLAY 0.617021 (-3110 5025);
PAINT SKYBLUE (-3110 5025);
FORCEPROP 1 LAST TOLERANCE 1%
J 0
(-3105 5125);
DISPLAY 0.617021 (-3105 5125);
PAINT SKYBLUE (-3105 5125);
FORCEPROP 1 LAST LOCATION R8D26
J 0
(-3105 5225);
DISPLAY 0.617021 (-3105 5225);
PAINT AQUA (-3105 5225);
FORCEPROP 1 LAST VALUE 4.75K
J 0
(-3105 5175);
DISPLAY 0.617021 (-3105 5175);
PAINT SKYBLUE (-3105 5175);
FORCEPROP 1 LAST WATTAGE 1/16W
J 0
(-3110 5075);
DISPLAY 0.617021 (-3110 5075);
PAINT SKYBLUE (-3110 5075);
FORCEPROP 2 LAST CDS_LIB mstr_discrete
J 0
(-3150 5100);
PAINT MONO (-3150 5100);
DISPLAY INVISIBLE (-3150 5100);
FORCEPROP 2 LAST ROOM FAST_PROCHOT
J 0
(-3100 5275);
DISPLAY 1.021277 (-3100 5275);
PAINT ORANGE (-3100 5275);
DISPLAY INVISIBLE (-3100 5275);
FORCEPROP 2 LAST SEC_TYPE 0402
J 0
(-3100 5325);
DISPLAY 1.021277 (-3100 5325);
PAINT ORANGE (-3100 5325);
DISPLAY INVISIBLE (-3100 5325);
FORCEPROP 2 LAST BOM_COST FAST_PROCHOT
J 0
(-3100 5325);
DISPLAY 1.021277 (-3100 5325);
PAINT ORANGE (-3100 5325);
DISPLAY INVISIBLE (-3100 5325);
FORCEPROP 2 LAST SEC 1
J 0
(-3100 5325);
PAINT MONO (-3100 5325);
DISPLAY INVISIBLE (-3100 5325);
FORCEPROP 1 LAST PATH I71
J 0
(-3100 5275);
DISPLAY 0.978723 (-3100 5275);
PAINT WHITE (-3100 5275);
DISPLAY INVISIBLE (-3100 5275);
FORCEPROP 2 LAST CDS_LOCATION R8D26
J 0
(-3105 5225);
DISPLAY 0.617021 (-3105 5225);
PAINT AQUA (-3105 5225);
DISPLAY INVISIBLE (-3105 5225);
FORCEADD P3V3_STBY..1
(-2025 3075);
FORCEPROP 3 LASTPIN (-2025 3025) SIG_NAME P3V3_STBY\g
J 0
(-2015 3035);
DISPLAY 0.659574 (-2015 3035);
PAINT MONO (-2015 3035);
DISPLAY INVISIBLE (-2015 3035);
FORCEPROP 1 LAST VOLTAGE 3.3V
J 0
(-2070 3032);
DISPLAY 0.340426 (-2070 3032);
PAINT SKYBLUE (-2070 3032);
DISPLAY INVISIBLE (-2070 3032);
FORCEPROP 1 LAST PATH I72
J 0
(-1980 3077);
DISPLAY 0.340426 (-1980 3077);
PAINT GREEN (-1980 3077);
DISPLAY INVISIBLE (-1980 3077);
FORCEPROP 1 LAST SIZE 1B
J 0
(-1980 3097);
DISPLAY 0.340426 (-1980 3097);
PAINT GREEN (-1980 3097);
DISPLAY INVISIBLE (-1980 3097);
FORCEPROP 2 LAST CDS_LIB mstr_symbols
J 0
(-2025 3075);
PAINT ORANGE (-2025 3075);
DISPLAY INVISIBLE (-2025 3075);
FORCEPROP 1 LAST BODY_TYPE PLUMBING
J 0
(-2070 3032);
DISPLAY 0.340426 (-2070 3032);
PAINT GREEN (-2070 3032);
DISPLAY INVISIBLE (-2070 3032);
FORCEPROP 1 LAST HDL_POWER P3V3_STBY
J 0
(-2325 2950);
DISPLAY 0.872340 (-2325 2950);
PAINT ORANGE (-2325 2950);
DISPLAY INVISIBLE (-2325 2950);
FORCEADD RES..2
(-2025 2850);
FORCEPROP 1 LASTPIN (-2025 2750) $PN 2
J 0
(-2020 2760);
DISPLAY 0.617021 (-2020 2760);
PAINT ORANGE (-2020 2760);
FORCEPROP 1 LAST MATERIAL CHIP
J 0
(-1985 2775);
DISPLAY 0.617021 (-1985 2775);
PAINT SKYBLUE (-1985 2775);
FORCEPROP 1 LAST PACK_TYPE 0402
J 0
(-1985 2675);
DISPLAY 0.617021 (-1985 2675);
PAINT SKYBLUE (-1985 2675);
FORCEPROP 1 LAST TOLERANCE 1%
J 0
(-1980 2875);
DISPLAY 0.617021 (-1980 2875);
PAINT SKYBLUE (-1980 2875);
FORCEPROP 1 LASTPIN (-2025 2950) $PN 1
J 0
(-2020 2912);
DISPLAY 0.617021 (-2020 2912);
PAINT ORANGE (-2020 2912);
FORCEPROP 1 LAST LOCATION R1R5
J 0
(-1980 2975);
DISPLAY 0.617021 (-1980 2975);
PAINT AQUA (-1980 2975);
FORCEPROP 1 LAST VALUE 4.75K
J 0
(-1980 2925);
DISPLAY 0.617021 (-1980 2925);
PAINT SKYBLUE (-1980 2925);
FORCEPROP 1 LAST WATTAGE 1/16W
J 0
(-1985 2825);
DISPLAY 0.617021 (-1985 2825);
PAINT SKYBLUE (-1985 2825);
FORCEPROP 1 LAST PART_NUMBER G21796-072
J 0
(-1985 2725);
DISPLAY 0.617021 (-1985 2725);
PAINT BLUE (-1985 2725);
FORCEPROP 2 LAST CDS_LIB mstr_discrete
J 0
(-2025 2850);
PAINT MONO (-2025 2850);
DISPLAY INVISIBLE (-2025 2850);
FORCEPROP 2 LAST CDS_LOCATION R1R5
J 0
(-1980 2975);
DISPLAY 0.617021 (-1980 2975);
PAINT AQUA (-1980 2975);
DISPLAY INVISIBLE (-1980 2975);
FORCEPROP 2 LAST ROOM FAST_PROCHOT
J 0
(-1975 3025);
DISPLAY 1.021277 (-1975 3025);
PAINT ORANGE (-1975 3025);
DISPLAY INVISIBLE (-1975 3025);
FORCEPROP 1 LAST PATH I73
J 0
(-1975 3025);
DISPLAY 0.978723 (-1975 3025);
PAINT WHITE (-1975 3025);
DISPLAY INVISIBLE (-1975 3025);
FORCEPROP 2 LAST SEC 1
J 0
(-1975 3075);
PAINT MONO (-1975 3075);
DISPLAY INVISIBLE (-1975 3075);
FORCEPROP 2 LAST SEC_TYPE 0402
J 0
(-1975 3075);
DISPLAY 1.021277 (-1975 3075);
PAINT ORANGE (-1975 3075);
DISPLAY INVISIBLE (-1975 3075);
FORCEPROP 2 LAST BOM_COST FAST_PROCHOT
J 0
(-1975 3075);
DISPLAY 1.021277 (-1975 3075);
PAINT ORANGE (-1975 3075);
DISPLAY INVISIBLE (-1975 3075);
FORCEADD RES..1
(-1675 4775);
FORCEPROP 1 LAST PACK_TYPE 0402
J 0
(-1550 4625);
DISPLAY 0.617021 (-1550 4625);
PAINT SKYBLUE (-1550 4625);
FORCEPROP 1 LASTPIN (-1575 4775) $PN 2
J 0
(-1613 4787);
DISPLAY 0.787234 (-1613 4787);
PAINT ORANGE (-1613 4787);
FORCEPROP 1 LASTPIN (-1775 4775) $PN 1
J 0
(-1763 4787);
DISPLAY 0.787234 (-1763 4787);
PAINT ORANGE (-1763 4787);
FORCEPROP 1 LAST MATERIAL CHIP
J 0
(-1675 4625);
DISPLAY 0.617021 (-1675 4625);
PAINT SKYBLUE (-1675 4625);
FORCEPROP 1 LAST PART_NUMBER G21796-074
J 0
(-1725 4875);
DISPLAY 0.617021 (-1725 4875);
PAINT BLUE (-1725 4875);
FORCEPROP 1 LAST LOCATION R2P4
J 0
(-1725 4825);
DISPLAY 0.617021 (-1725 4825);
PAINT AQUA (-1725 4825);
FORCEPROP 1 LAST WATTAGE 1/16W
J 2
(-1700 4625);
DISPLAY 0.617021 (-1700 4625);
PAINT SKYBLUE (-1700 4625);
FORCEPROP 1 LAST TOLERANCE 1%
J 0
(-1675 4675);
DISPLAY 0.617021 (-1675 4675);
PAINT SKYBLUE (-1675 4675);
FORCEPROP 1 LAST VALUE 33.2
J 2
(-1700 4675);
DISPLAY 0.617021 (-1700 4675);
PAINT SKYBLUE (-1700 4675);
FORCEPROP 2 LAST SEC 1
J 0
(-1725 4975);
PAINT MONO (-1725 4975);
DISPLAY INVISIBLE (-1725 4975);
FORCEPROP 2 LAST SEC_TYPE 0402
J 0
(-1725 4975);
DISPLAY 1.021277 (-1725 4975);
PAINT ORANGE (-1725 4975);
DISPLAY INVISIBLE (-1725 4975);
FORCEPROP 1 LAST PATH I74
J 0
(-1725 4925);
DISPLAY 0.978723 (-1725 4925);
PAINT WHITE (-1725 4925);
DISPLAY INVISIBLE (-1725 4925);
FORCEPROP 2 LAST CDS_LIB mstr_discrete
J 0
(-1675 4775);
PAINT ORANGE (-1675 4775);
DISPLAY INVISIBLE (-1675 4775);
FORCEPROP 2 LAST CDS_LOCATION R2P4
J 0
(-1725 4825);
DISPLAY 0.617021 (-1725 4825);
PAINT AQUA (-1725 4825);
DISPLAY INVISIBLE (-1725 4825);
FORCEADD RES..2
(-3825 5100);
FORCEPROP 1 LAST TOLERANCE 1%
J 0
(-3780 5125);
DISPLAY 0.617021 (-3780 5125);
PAINT SKYBLUE (-3780 5125);
FORCEPROP 1 LASTPIN (-3825 5200) $PN 1
J 0
(-3820 5162);
DISPLAY 0.617021 (-3820 5162);
PAINT ORANGE (-3820 5162);
FORCEPROP 1 LASTPIN (-3825 5000) $PN 2
J 0
(-3820 5010);
DISPLAY 0.617021 (-3820 5010);
PAINT ORANGE (-3820 5010);
FORCEPROP 1 LAST MATERIAL CHIP
J 0
(-3785 5025);
DISPLAY 0.617021 (-3785 5025);
PAINT SKYBLUE (-3785 5025);
FORCEPROP 1 LAST PACK_TYPE 0402
J 0
(-3785 4925);
DISPLAY 0.617021 (-3785 4925);
PAINT SKYBLUE (-3785 4925);
FORCEPROP 1 LAST PART_NUMBER G21796-072
J 0
(-3785 4975);
DISPLAY 0.617021 (-3785 4975);
PAINT BLUE (-3785 4975);
FORCEPROP 1 LAST WATTAGE 1/16W
J 0
(-3785 5075);
DISPLAY 0.617021 (-3785 5075);
PAINT SKYBLUE (-3785 5075);
FORCEPROP 1 LAST VALUE 4.75K
J 0
(-3780 5175);
DISPLAY 0.617021 (-3780 5175);
PAINT SKYBLUE (-3780 5175);
FORCEPROP 1 LAST LOCATION R2P8
J 0
(-3780 5225);
DISPLAY 0.617021 (-3780 5225);
PAINT AQUA (-3780 5225);
FORCEPROP 0 LAST BOM_COST PROC_SIDEBAND
J 0
(-3775 5325);
DISPLAY 1.021277 (-3775 5325);
PAINT ORANGE (-3775 5325);
DISPLAY INVISIBLE (-3775 5325);
FORCEPROP 2 LAST SEC_TYPE 0402
J 0
(-3775 5325);
DISPLAY 1.021277 (-3775 5325);
PAINT ORANGE (-3775 5325);
DISPLAY INVISIBLE (-3775 5325);
FORCEPROP 2 LAST SEC 1
J 0
(-3775 5325);
DISPLAY 0.680851 (-3775 5325);
PAINT MONO (-3775 5325);
DISPLAY INVISIBLE (-3775 5325);
FORCEPROP 0 LAST ROOM PROC_SIDEBAND
J 0
(-3775 5325);
DISPLAY 1.021277 (-3775 5325);
PAINT ORANGE (-3775 5325);
DISPLAY INVISIBLE (-3775 5325);
FORCEPROP 2 LAST CDS_LIB mstr_discrete
J 0
(-3825 5100);
PAINT MONO (-3825 5100);
DISPLAY INVISIBLE (-3825 5100);
FORCEPROP 1 LAST PATH I75
J 0
(-3775 5275);
DISPLAY 0.978723 (-3775 5275);
PAINT WHITE (-3775 5275);
DISPLAY INVISIBLE (-3775 5275);
FORCEPROP 2 LAST CDS_LOCATION R2P8
J 0
(-3780 5225);
DISPLAY 0.617021 (-3780 5225);
PAINT AQUA (-3780 5225);
DISPLAY INVISIBLE (-3780 5225);
FORCEADD CAP_A..1
(-5100 3350);
FORCEPROP 1 LAST LOCATION C2P1
J 0
(-5050 3450);
DISPLAY 0.617021 (-5050 3450);
PAINT AQUA (-5050 3450);
FORCEPROP 1 LAST VALUE 0.1UF
J 0
(-5050 3400);
DISPLAY 0.617021 (-5050 3400);
PAINT SKYBLUE (-5050 3400);
FORCEPROP 1 LASTPIN (-5100 3250) $PN 2
J 0
(-5090 3230);
DISPLAY 0.617021 (-5090 3230);
PAINT ORANGE (-5090 3230);
FORCEPROP 1 LAST MATERIAL X7R
J 0
(-5050 3250);
DISPLAY 0.617021 (-5050 3250);
PAINT SKYBLUE (-5050 3250);
FORCEPROP 1 LAST TOLERANCE 10%
J 0
(-5050 3300);
DISPLAY 0.617021 (-5050 3300);
PAINT SKYBLUE (-5050 3300);
FORCEPROP 1 LAST PACK_TYPE 0402V
J 0
(-5050 3150);
DISPLAY 0.617021 (-5050 3150);
PAINT SKYBLUE (-5050 3150);
FORCEPROP 1 LASTPIN (-5100 3450) $PN 1
J 0
(-5090 3430);
DISPLAY 0.617021 (-5090 3430);
PAINT ORANGE (-5090 3430);
FORCEPROP 1 LAST VOLTAGE 16V
J 0
(-5050 3350);
DISPLAY 0.617021 (-5050 3350);
PAINT SKYBLUE (-5050 3350);
FORCEPROP 1 LAST PART_NUMBER A36096-030
J 0
(-5050 3200);
DISPLAY 0.617021 (-5050 3200);
PAINT BLUE (-5050 3200);
FORCEPROP 2 LAST CDS_LOCATION C2P1
J 0
(-5050 3450);
DISPLAY 0.617021 (-5050 3450);
PAINT AQUA (-5050 3450);
DISPLAY INVISIBLE (-5050 3450);
FORCEPROP 2 LAST CDS_LIB dev_discrete
J 0
(-5100 3350);
PAINT ORANGE (-5100 3350);
DISPLAY INVISIBLE (-5100 3350);
FORCEPROP 2 LAST CDS_SEC 1
J 0
(-5050 3500);
PAINT ORANGE (-5050 3500);
DISPLAY INVISIBLE (-5050 3500);
FORCEPROP 2 LAST SEC 1
J 0
(-5050 3550);
DISPLAY 0.680851 (-5050 3550);
PAINT MONO (-5050 3550);
DISPLAY INVISIBLE (-5050 3550);
FORCEPROP 2 LAST ROOM FAST_PROCHOT
J 0
(-5050 3500);
DISPLAY 1.021277 (-5050 3500);
PAINT ORANGE (-5050 3500);
DISPLAY INVISIBLE (-5050 3500);
FORCEPROP 1 LAST PATH I8
J 0
(-5050 3500);
DISPLAY 0.978723 (-5050 3500);
PAINT WHITE (-5050 3500);
DISPLAY INVISIBLE (-5050 3500);
FORCEPROP 2 LAST SEC_TYPE 0402V
J 0
(-5050 3550);
DISPLAY 1.021277 (-5050 3550);
PAINT ORANGE (-5050 3550);
DISPLAY INVISIBLE (-5050 3550);
FORCEPROP 2 LAST BOM_COST FAST_PROCHOT
J 0
(-5050 3550);
DISPLAY 1.021277 (-5050 3550);
PAINT ORANGE (-5050 3550);
DISPLAY INVISIBLE (-5050 3550);
FORCEADD DESIGN_NOTE..1
(-4625 3550);
FORCEPROP 0 LAST L1 74LVC1G07 USED TO MAKE IRQ_SML1_PMBUS_ALERT_BUF_N
J 0
(-4825 3425);
DISPLAY 0.808511 (-4825 3425);
PAINT ORANGE (-4825 3425);
FORCEPROP 0 LAST L2 AN OPEN DRAIN NET. IRQ_SML1_PMBUS_ALERT_BUF_N
J 0
(-4825 3375);
DISPLAY 0.808511 (-4825 3375);
PAINT ORANGE (-4825 3375);
FORCEPROP 0 LAST L3 COMES FROM A PUSH-PULL TRI-STATE BUFFER
J 0
(-4825 3325);
DISPLAY 0.808511 (-4825 3325);
PAINT ORANGE (-4825 3325);
FORCEPROP 2 LAST CDS_LIB mstr_symbols
J 0
(-4625 3550);
PAINT MONO (-4625 3550);
DISPLAY INVISIBLE (-4625 3550);
FORCEPROP 1 LAST COMMENT_BODY TRUE
J 0
(-4600 3650);
DISPLAY 0.978723 (-4600 3650);
PAINT ORANGE (-4600 3650);
DISPLAY INVISIBLE (-4600 3650);
FORCEADD CAD_NOTE..1
(-4675 3250);
FORCEPROP 0 LAST L1 PLACE CAP CLOSE TO VCC ON
J 0
(-4825 3125);
DISPLAY 1.021277 (-4825 3125);
PAINT ORANGE (-4825 3125);
FORCEPROP 0 LAST L2 1G07 BUFFER
J 0
(-4825 3075);
DISPLAY 1.021277 (-4825 3075);
PAINT ORANGE (-4825 3075);
FORCEPROP 2 LAST CDS_LIB mstr_symbols
J 0
(-4675 3250);
PAINT ORANGE (-4675 3250);
DISPLAY INVISIBLE (-4675 3250);
FORCEPROP 1 LAST COMMENT_BODY TRUE
J 0
(-4650 3350);
DISPLAY 0.978723 (-4650 3350);
PAINT ORANGE (-4650 3350);
DISPLAY INVISIBLE (-4650 3350);
FORCEADD CAD_NOTE..1
(-1125 1875);
FORCEPROP 0 LAST L1 PLACE CAP CLOSE TO VCC ON
J 0
(-1275 1750);
DISPLAY 1.021277 (-1275 1750);
PAINT ORANGE (-1275 1750);
FORCEPROP 0 LAST L2 74LVC1G07
J 0
(-1275 1700);
DISPLAY 1.021277 (-1275 1700);
PAINT ORANGE (-1275 1700);
FORCEPROP 2 LAST CDS_LIB mstr_symbols
J 0
(-1125 1875);
PAINT ORANGE (-1125 1875);
DISPLAY INVISIBLE (-1125 1875);
FORCEPROP 1 LAST COMMENT_BODY TRUE
J 0
(-1100 1975);
DISPLAY 0.978723 (-1100 1975);
PAINT ORANGE (-1100 1975);
DISPLAY INVISIBLE (-1100 1975);
FORCEADD CAD_NOTE..1
(-4675 1500);
FORCEPROP 0 LAST L1 PLACE CAP CLOSE TO VCC ON
J 0
(-4825 1375);
DISPLAY 1.021277 (-4825 1375);
PAINT ORANGE (-4825 1375);
FORCEPROP 0 LAST L2 74HC1G126
J 0
(-4825 1325);
DISPLAY 1.021277 (-4825 1325);
PAINT ORANGE (-4825 1325);
FORCEPROP 2 LAST CDS_LIB mstr_symbols
J 0
(-4675 1500);
PAINT ORANGE (-4675 1500);
DISPLAY INVISIBLE (-4675 1500);
FORCEPROP 1 LAST COMMENT_BODY TRUE
J 0
(-4650 1600);
DISPLAY 0.978723 (-4650 1600);
PAINT ORANGE (-4650 1600);
DISPLAY INVISIBLE (-4650 1600);
FORCEADD INTEL_CORP_BPAGE..1
(2100 700);
FORCEPROP 1 LAST CDS_CON_LAST_MODIFIED Fri Jun 16 17:49:02 2017
J 0
(675 1025);
PAINT ORANGE (675 1025);
DISPLAY INVISIBLE (675 1025);
FORCEPROP 1 LAST CUSTOM_TXT_CDS <CURRENT_DESIGN_SHEET> OF <TOTAL_DESIGN_SHEETS>
J 0
(1600 725);
PAINT ORANGE (1600 725);
FORCEPROP 1 LAST CUSTOM_TXT_CDS <CON_LAST_MODIFIED>
J 0
(-1900 800);
PAINT ORANGE (-1900 800);
FORCEPROP 2 LAST CUSTOM_TXT_CDS <XR_PAGE_TITLE>
J 0
(-5790 5950);
DISPLAY 0.638298 (-5790 5950);
PAINT PINK (-5790 5950);
DISPLAY INVISIBLE (-5790 5950);
FORCEPROP 1 LAST SCH_TITLE FAST PROCHOT LOGIC
J 0
(-5850 750);
DISPLAY 1.212766 (-5850 750);
PAINT ORANGE (-5850 750);
FORCEPROP 2 LAST PAGE_BORDER TRUE
J 0
(-5790 5950);
DISPLAY 0.851064 (-5790 5950);
PAINT PINK (-5790 5950);
DISPLAY INVISIBLE (-5790 5950);
FORCEPROP 2 LAST CDS_LIB mstr_symbols
J 0
(2100 700);
PAINT MONO (2100 700);
DISPLAY INVISIBLE (2100 700);
FORCEPROP 1 LAST COMMENT_BODY TRUE
J 0
(2112 712);
DISPLAY 0.468085 (2112 712);
PAINT GREEN (2112 712);
DISPLAY INVISIBLE (2112 712);
FORCEPROP 2 LAST CDS_XR_PAGE_TITLE CR-170 : @BASEBOARD_FAB2_LIB.BASEBOARD_FAB2(SCH_1):PAGE170
J 0
(-5790 5950);
DISPLAY 0.638298 (-5790 5950);
PAINT PINK (-5790 5950);
DISPLAY INVISIBLE (-5790 5950);
FORCEADD DNS..2
(-4520 3920);
PAINT RED (-4520 3920);
FORCEPROP 2 LAST CDS_LIB mstr_misc
J 0
(-4520 3920);
PAINT ORANGE (-4520 3920);
DISPLAY INVISIBLE (-4520 3920);
FORCEPROP 1 LAST COMMENT_BODY TRUE
R 1
J 0
(-4445 3695);
DISPLAY 0.872340 (-4445 3695);
PAINT GREEN (-4445 3695);
DISPLAY INVISIBLE (-4445 3695);
FORCEADD CAD_NOTE..1
(-875 5275);
FORCEPROP 0 LAST L2 TRI STATE BUFFER
J 0
(-1025 5075);
DISPLAY 1.021277 (-1025 5075);
PAINT ORANGE (-1025 5075);
FORCEPROP 0 LAST L1 PLACE CAP CLOSE TO VCC ON
J 0
(-1025 5150);
DISPLAY 1.021277 (-1025 5150);
PAINT ORANGE (-1025 5150);
FORCEPROP 2 LAST CDS_LIB mstr_symbols
J 0
(-875 5275);
PAINT ORANGE (-875 5275);
DISPLAY INVISIBLE (-875 5275);
FORCEPROP 1 LAST COMMENT_BODY TRUE
J 0
(-850 5375);
DISPLAY 0.978723 (-850 5375);
PAINT ORANGE (-850 5375);
DISPLAY INVISIBLE (-850 5375);
FORCEADD CAD_NOTE..1
(275 4950);
FORCEPROP 0 LAST L2 74LVC08
J 0
(125 4775);
DISPLAY 1.021277 (125 4775);
PAINT ORANGE (125 4775);
FORCEPROP 0 LAST L1 PLACE CAP CLOSE TO VCC ON
J 0
(125 4825);
DISPLAY 1.021277 (125 4825);
PAINT ORANGE (125 4825);
FORCEPROP 2 LAST CDS_LIB mstr_symbols
J 0
(275 4950);
PAINT ORANGE (275 4950);
DISPLAY INVISIBLE (275 4950);
FORCEPROP 1 LAST COMMENT_BODY TRUE
J 0
(300 5050);
DISPLAY 0.978723 (300 5050);
PAINT ORANGE (300 5050);
DISPLAY INVISIBLE (300 5050);
FORCEADD DNS..2
(-3695 4245);
PAINT RED (-3695 4245);
FORCEPROP 2 LAST CDS_LIB mstr_misc
J 0
(-3695 4245);
PAINT ORANGE (-3695 4245);
DISPLAY INVISIBLE (-3695 4245);
FORCEPROP 1 LAST COMMENT_BODY TRUE
R 1
J 0
(-3620 4020);
DISPLAY 0.872340 (-3620 4020);
PAINT GREEN (-3620 4020);
DISPLAY INVISIBLE (-3620 4020);
WIRE 16 -1 (-2125 5425)(-2125 5350);
WIRE 16 -1 (-5150 1100)(-5150 1225);
WIRE 16 -1 (-5150 1425)(-5150 1525);
WIRE 16 -1 (-200 4550)(-200 4675);
WIRE 16 -1 (-200 4875)(-200 4975);
WIRE 16 -1 (-1350 5200)(-1350 5300);
WIRE 16 -1 (-1350 4875)(-1350 5000);
WIRE 16 -1 (-3700 4000)(-3700 4150);
WIRE 16 -1 (-1600 1800)(-1600 1900);
WIRE 16 -1 (-1600 1475)(-1600 1600);
WIRE 16 -1 (-3825 5425)(-3825 5275);
WIRE 16 -1 (-4150 5275)(-3825 5275);
WIRE 16 -1 (-3825 5275)(-3825 5200);
WIRE 16 -1 (-4150 5275)(-4150 5200);
WIRE 16 -1 (-3450 2300)(-3450 2175);
WIRE 16 -1 (-5100 3450)(-5100 3550);
WIRE 16 -1 (-4150 3950)(-4150 4025);
WIRE 16 -1 (-4600 4450)(-4600 4525);
WIRE 16 -1 (-4525 3750)(-4525 3825);
WIRE 16 -1 (-2950 2950)(-2950 2875);
WIRE 16 -1 (-2950 1625)(-2950 1700);
WIRE 16 -1 (-5100 3125)(-5100 3250);
WIRE 16 -1 (-3150 5425)(-3150 5200);
WIRE 16 -1 (-2025 3025)(-2025 2950);
WIRE 16 -1 (-3700 4350)(-3700 4775);
WIRE 16 -1 (-3700 4775)(-3650 4775);
WIRE 16 -1 (-3700 4775)(-3825 4775);
WIRE 16 -1 (-3825 5000)(-3825 4775);
WIRE 16 -1 (-4950 4775)(-3825 4775);
FORCEPROP 2 LAST SIG_NAME IRQ_SML1_PMBUS_ALERT_N
J 0
(-4950 4785);
DISPLAY 0.617021 (-4950 4785);
PAINT ORANGE (-4950 4785);
WIRE 16 -1 (-4150 4425)(-4150 4600);
WIRE 16 -1 (-4150 4600)(-4150 5000);
WIRE 16 -1 (-4150 4600)(-3500 4600);
FORCEPROP 2 LAST SIG_NAME FM_PMBUS_ALERT_BUF_EN
J 0
(-4135 4610);
DISPLAY 0.617021 (-4135 4610);
PAINT ORANGE (-4135 4610);
FORCEPROP 2 LASTPROP $XRERR UNIQUE?
J 0
(-4375 4610);
DISPLAY 0.638298 (-4375 4610);
PAINT MONO (-4375 4610);
DISPLAY INVISIBLE (-4375 4610);
WIRE 16 -1 (-3500 4600)(-3500 4675);
WIRE 3 682 (-3600 4900)(-3900 4900);
WIRE 3 682 (-3600 5350)(-3600 4900);
WIRE 3 682 (-3900 4900)(-3900 5350);
WIRE 3 682 (-3900 5350)(-3600 5350);
WIRE 16 -1 (-4525 4025)(-4525 4125);
WIRE 16 -1 (-4525 4125)(-4350 4125);
WIRE 16 -1 (-4600 4125)(-4525 4125);
WIRE 16 -1 (-4600 4250)(-4600 4125);
WIRE 16 -1 (-4950 4125)(-4600 4125);
FORCEPROP 2 LAST SIG_NAME FM_PMBUS_ALERT_BUF_EN_N
J 0
(-4960 4135);
DISPLAY 0.617021 (-4960 4135);
PAINT ORANGE (-4960 4135);
WIRE 16 -1 (-3700 2525)(-2675 2525);
FORCEPROP 2 LAST SIG_NAME FM_FAST_PROCHOT_THROTTLE_DLY_N
J 0
(-3660 2535);
DISPLAY 0.617021 (-3660 2535);
PAINT ORANGE (-3660 2535);
WIRE 16 -1 (-2525 2250)(-2525 2425);
WIRE 16 -1 (-2950 2100)(-2950 2250);
WIRE 16 -1 (-2950 2250)(-2950 2675);
WIRE 16 -1 (-2950 2250)(-2525 2250);
FORCEPROP 2 LAST SIG_NAME FM_FAST_PROCHOT_EN
J 0
(-2935 2260);
DISPLAY 0.617021 (-2935 2260);
PAINT ORANGE (-2935 2260);
FORCEPROP 2 LASTPROP $XRERR UNIQUE?
J 0
(-3175 2260);
DISPLAY 0.638298 (-3175 2260);
PAINT MONO (-3175 2260);
DISPLAY INVISIBLE (-3175 2260);
WIRE 16 -1 (-2025 2525)(-2375 2525);
FORCEPROP 2 LAST SIG_NAME FM_FAST_PROCHOT_THROTTLE_DLY_BUF_N
J 0
(-2360 2535);
DISPLAY 0.617021 (-2360 2535);
PAINT ORANGE (-2360 2535);
FORCEPROP 2 LASTPROP $XRERR UNIQUE?
J 0
(-2600 2535);
DISPLAY 0.638298 (-2600 2535);
PAINT MONO (-2600 2535);
DISPLAY INVISIBLE (-2600 2535);
WIRE 16 -1 (-2025 2750)(-2025 2525);
WIRE 16 -1 (-1325 2525)(-2025 2525);
WIRE 16 -1 (-575 2525)(-1075 2525);
FORCEPROP 0 LAST SIG_NAME FM_THROTTLE_R1_N
J 0
(-1010 2535);
DISPLAY 0.617021 (-1010 2535);
PAINT ORANGE (-1010 2535);
FORCEPROP 2 LASTPROP $XRERR UNIQUE?
J 0
(-1250 2535);
DISPLAY 0.638298 (-1250 2535);
PAINT MONO (-1250 2535);
DISPLAY INVISIBLE (-1250 2535);
WIRE 16 -1 (-375 2525)(75 2525);
FORCEPROP 2 LAST SIG_NAME FM_THROTTLE_N
J 0
(-360 2535);
DISPLAY 0.617021 (-360 2535);
PAINT ORANGE (-360 2535);
WIRE 16 -1 (-3450 1975)(-3450 1800);
WIRE 16 -1 (-3450 1800)(-3150 1800);
WIRE 16 -1 (-3950 1800)(-3450 1800);
FORCEPROP 2 LAST SIG_NAME FM_FAST_PROCHOT_EN_N
J 0
(-3910 1810);
DISPLAY 0.617021 (-3910 1810);
PAINT ORANGE (-3910 1810);
WIRE 16 -1 (-3150 5000)(-3150 4775);
WIRE 16 -1 (-3150 4775)(-2500 4775);
WIRE 16 -1 (-3350 4775)(-3150 4775);
FORCEPROP 2 LAST SIG_NAME IRQ_SML1_PMBUS_ALERT_BUF_N
J 0
(-3310 4785);
DISPLAY 0.617021 (-3310 4785);
PAINT ORANGE (-3310 4785);
FORCEPROP 2 LASTPROP $XRERR UNIQUE?
J 0
(-3550 4785);
DISPLAY 0.638298 (-3550 4785);
PAINT MONO (-3550 4785);
DISPLAY INVISIBLE (-3550 4785);
WIRE 16 -1 (-2250 4775)(-2125 4775);
WIRE 16 -1 (-2125 4775)(-1775 4775);
WIRE 16 -1 (-2125 5150)(-2125 4775);
FORCEPROP 2 LAST SIG_NAME IRQ_FORCE_NM_THROTTLE_R_N
J 0
(-2110 5010);
DISPLAY 0.617021 (-2110 5010);
PAINT ORANGE (-2110 5010);
FORCEPROP 2 LASTPROP $XRERR UNIQUE?
J 0
(-2350 5010);
DISPLAY 0.638298 (-2350 5010);
PAINT MONO (-2350 5010);
DISPLAY INVISIBLE (-2350 5010);
WIRE 16 -1 (125 4075)(975 4075);
FORCEPROP 2 LAST SIG_NAME FM_FAST_PROCHOT_THROTTLE_IN_N
J 0
(190 4085);
DISPLAY 0.617021 (190 4085);
PAINT ORANGE (190 4085);
WIRE 16 -1 (-2200 3700)(-1325 3700);
FORCEPROP 2 LAST SIG_NAME IRQ_UV_DETECT_N
J 0
(-2135 3710);
DISPLAY 0.617021 (-2135 3710);
PAINT ORANGE (-2135 3710);
WIRE 16 -1 (-2200 3600)(-1325 3600);
FORCEPROP 2 LAST SIG_NAME FM_HSC_TIMER_EXP_N
J 0
(-2135 3610);
DISPLAY 0.617021 (-2135 3610);
PAINT ORANGE (-2135 3610);
WIRE 16 -1 (-1425 4425)(-2250 4425);
FORCEPROP 2 LAST SIG_NAME IRQ_FORCE_NM_THROTTLE_N
J 0
(-2210 4435);
DISPLAY 0.617021 (-2210 4435);
PAINT ORANGE (-2210 4435);
WIRE 16 -1 (-1425 4425)(-1325 4425);
WIRE 16 -1 (-1575 4775)(-1425 4775);
WIRE 16 -1 (-1425 4775)(-1425 4425);
WIRE 16 -1 (-550 4125)(-175 4125);
WIRE 16 -1 (-550 4375)(-550 4125);
WIRE 16 -1 (-1025 4375)(-550 4375);
FORCEPROP 2 LAST SIG_NAME FM_FAST_PROCHOT_AND_OUT_0_N
J 0
(-960 4385);
DISPLAY 0.617021 (-960 4385);
PAINT ORANGE (-960 4385);
FORCEPROP 2 LASTPROP $XRERR UNIQUE?
J 0
(-1200 4385);
DISPLAY 0.638298 (-1200 4385);
PAINT MONO (-1200 4385);
DISPLAY INVISIBLE (-1200 4385);
WIRE 16 -1 (-525 4025)(-175 4025);
WIRE 16 -1 (-525 3650)(-525 4025);
WIRE 16 -1 (-1025 3650)(-525 3650);
FORCEPROP 2 LAST SIG_NAME FM_FAST_PROCHOT_AND_OUT_1_N
J 0
(-960 3660);
DISPLAY 0.617021 (-960 3660);
PAINT ORANGE (-960 3660);
FORCEPROP 2 LASTPROP $XRERR UNIQUE?
J 0
(-1200 3660);
DISPLAY 0.638298 (-1200 3660);
PAINT MONO (-1200 3660);
DISPLAY INVISIBLE (-1200 3660);
WIRE 16 -1 (-2250 4325)(-1325 4325);
FORCEPROP 2 LAST SIG_NAME FM_OC_DETECT_N
J 0
(-2210 4335);
DISPLAY 0.617021 (-2210 4335);
PAINT ORANGE (-2210 4335);
DOT 1 (-2125 4775);
DOT 1 (-1425 4425);
DOT 1 (-3150 4775);
DOT 1 (-2025 2525);
DOT 1 (-4600 4125);
DOT 1 (-4525 4125);
DOT 1 (-4150 4600);
DOT 1 (-3450 1800);
DOT 1 (-2950 2250);
DOT 1 (-3825 4775);
DOT 1 (-3700 4775);
DOT 1 (-3825 5275);
FORCENOTE
FROM HSC TIMER
(-2900 3475) 0;
DISPLAY LEFT (-2900 3475);
DISPLAY 1.021277 (-2900 3475);
PAINT PURPLE (-2900 3475);
FORCENOTE
FROM UNDER VOLTAGE MONITOR
(-2925 3775) 0;
DISPLAY LEFT (-2925 3775);
DISPLAY 1.021277 (-2925 3775);
PAINT PURPLE (-2925 3775);
FORCENOTE
TO CPLD
(1025 3950) 0;
DISPLAY LEFT (1025 3950);
DISPLAY 1.021277 (1025 3950);
PAINT PURPLE (1025 3950);
FORCENOTE
FROM CPLD
(-4200 2575) 0;
DISPLAY LEFT (-4200 2575);
DISPLAY 1.021277 (-4200 2575);
PAINT PURPLE (-4200 2575);
FORCENOTE
FROM BMC AND IE
(-4425 2200) 0;
DISPLAY LEFT (-4425 2200);
DISPLAY 1.021277 (-4425 2200);
PAINT PURPLE (-4425 2200);
FORCENOTE
TP FAB1 CHANGE R2P8 RES 0523
(-3575 5275) 0;
DISPLAY LEFT (-3575 5275);
DISPLAY 1.021277 (-3575 5275);
PAINT RED (-3575 5275);
FORCENOTE
FROM OVER CURRENT MONITOR
(-2925 4200) 0;
DISPLAY LEFT (-2925 4200);
DISPLAY 1.021277 (-2925 4200);
PAINT PURPLE (-2925 4200);
QUIT
